FILE_TYPE = MACRO_DRAWING;
SET COLOR_WIRE YELLOW;
SET COLOR_PROP MONO;
SET COLOR_DOT WHITE;
SET COLOR_ARC YELLOW;
SET COLOR_BODY GREEN;
SET COLOR_NOTE MONO;
SET PROP_DISPLAY VALUE;
SET PAGE_NUMBER P270;
FORCEADD TEST-PAD-12P-1-GP-U..1
(-8825 5975);
FORCEPROP 2 LASTPIN (-8600 6200) $PN 2
J 0
(-8590 6210);
DISPLAY 0.808511 (-8590 6210);
PAINT ORANGE (-8590 6210);
FORCEPROP 2 LASTPIN (-8600 6250) $PN 1
J 0
(-8590 6260);
DISPLAY 0.808511 (-8590 6260);
PAINT ORANGE (-8590 6260);
FORCEPROP 2 LASTPIN (-8600 5700) $PN 12
J 0
(-8590 5710);
DISPLAY 0.808511 (-8590 5710);
PAINT ORANGE (-8590 5710);
FORCEPROP 2 LASTPIN (-8600 5750) $PN 11
J 0
(-8590 5760);
DISPLAY 0.808511 (-8590 5760);
PAINT ORANGE (-8590 5760);
FORCEPROP 2 LASTPIN (-8600 5800) $PN 10
J 0
(-8590 5810);
DISPLAY 0.808511 (-8590 5810);
PAINT ORANGE (-8590 5810);
FORCEPROP 2 LASTPIN (-8600 5850) $PN 9
J 0
(-8590 5860);
DISPLAY 0.808511 (-8590 5860);
PAINT ORANGE (-8590 5860);
FORCEPROP 2 LASTPIN (-8600 5900) $PN 8
J 0
(-8590 5910);
DISPLAY 0.808511 (-8590 5910);
PAINT ORANGE (-8590 5910);
FORCEPROP 2 LASTPIN (-8600 5950) $PN 7
J 0
(-8590 5960);
DISPLAY 0.808511 (-8590 5960);
PAINT ORANGE (-8590 5960);
FORCEPROP 2 LASTPIN (-8600 6000) $PN 6
J 0
(-8590 6010);
DISPLAY 0.808511 (-8590 6010);
PAINT ORANGE (-8590 6010);
FORCEPROP 2 LASTPIN (-8600 6050) $PN 5
J 0
(-8590 6060);
DISPLAY 0.808511 (-8590 6060);
PAINT ORANGE (-8590 6060);
FORCEPROP 2 LASTPIN (-8600 6150) $PN 3
J 0
(-8590 6160);
DISPLAY 0.808511 (-8590 6160);
PAINT ORANGE (-8590 6160);
FORCEPROP 1 LAST LOCATION T1D1
J 0
(-8800 6375);
DISPLAY 0.617021 (-8800 6375);
PAINT GREEN (-8800 6375);
FORCEPROP 1 LAST VALUE TEST-PAD-12P-1-GP-U
J 0
(-8900 5550);
DISPLAY 0.617021 (-8900 5550);
PAINT GREEN (-8900 5550);
FORCEPROP 2 LASTPIN (-8600 6100) $PN 4
J 0
(-8590 6110);
DISPLAY 0.808511 (-8590 6110);
PAINT ORANGE (-8590 6110);
FORCEPROP 1 LAST PATH I1
J 0
(-8825 6265);
DISPLAY 0.617021 (-8825 6265);
PAINT GREEN (-8825 6265);
DISPLAY INVISIBLE (-8825 6265);
FORCEPROP 1 LAST CDS_LMAN_SYM_OUTLINE -75,375,75,-375
J 0
(-8825 5975);
DISPLAY 0.468085 (-8825 5975);
PAINT GREEN (-8825 5975);
DISPLAY INVISIBLE (-8825 5975);
FORCEPROP 2 LAST CDS_LIB w_hdl
J 0
(-8825 5975);
DISPLAY INVISIBLE (-8825 5975);
FORCEPROP 1 LAST PART_NUMBER ZZ.00PAD.MJ1
J 0
(-8825 5686);
DISPLAY 0.617021 (-8825 5686);
PAINT GREEN (-8825 5686);
DISPLAY INVISIBLE (-8825 5686);
FORCEPROP 1 LAST PACK_TYPE DISCRET-GB1
J 0
(-8825 5975);
DISPLAY 0.617021 (-8825 5975);
PAINT GREEN (-8825 5975);
DISPLAY INVISIBLE (-8825 5975);
FORCEPROP 2 LAST SEC 1
J 0
(-8800 6425);
DISPLAY 0.680851 (-8800 6425);
PAINT MONO (-8800 6425);
DISPLAY INVISIBLE (-8800 6425);
FORCEPROP 2 LAST SEC_TYPE DISCRET-GB1
J 0
(-8800 6425);
DISPLAY 1.021277 (-8800 6425);
PAINT ORANGE (-8800 6425);
DISPLAY INVISIBLE (-8800 6425);
FORCEADD GND..1
(-7600 3700);
FORCEPROP 3 LASTPIN (-7600 3750) SIG_NAME GND\g
J 0
(-7590 3760);
DISPLAY 0.659574 (-7590 3760);
PAINT MONO (-7590 3760);
DISPLAY INVISIBLE (-7590 3760);
FORCEPROP 1 LAST PATH I10
J 0
(-7525 3700);
DISPLAY 0.872340 (-7525 3700);
PAINT AQUA (-7525 3700);
DISPLAY INVISIBLE (-7525 3700);
FORCEPROP 1 LAST VOLTAGE 0.0V
J 0
(-7645 3657);
DISPLAY 0.340426 (-7645 3657);
PAINT SKYBLUE (-7645 3657);
DISPLAY INVISIBLE (-7645 3657);
FORCEPROP 1 LAST SIZE 1B
J 0
(-7525 3650);
DISPLAY 2.382979 (-7525 3650);
PAINT GREEN (-7525 3650);
DISPLAY INVISIBLE (-7525 3650);
FORCEPROP 1 LAST BODY_TYPE PLUMBING
J 0
(-7645 3657);
DISPLAY 0.340426 (-7645 3657);
PAINT GREEN (-7645 3657);
DISPLAY INVISIBLE (-7645 3657);
FORCEPROP 1 LAST HDL_POWER GND
J 0
(-7600 3850);
PAINT GREEN (-7600 3850);
DISPLAY INVISIBLE (-7600 3850);
FORCEPROP 2 LAST CDS_LIB mstr_symbols
J 0
(-7600 3700);
DISPLAY INVISIBLE (-7600 3700);
FORCEADD GND..1
(-8450 3700);
FORCEPROP 3 LASTPIN (-8450 3750) SIG_NAME GND\g
J 0
(-8440 3760);
DISPLAY 0.659574 (-8440 3760);
PAINT MONO (-8440 3760);
DISPLAY INVISIBLE (-8440 3760);
FORCEPROP 1 LAST PATH I11
J 0
(-8375 3700);
DISPLAY 0.872340 (-8375 3700);
PAINT AQUA (-8375 3700);
DISPLAY INVISIBLE (-8375 3700);
FORCEPROP 2 LAST CDS_LIB mstr_symbols
J 0
(-8450 3700);
DISPLAY INVISIBLE (-8450 3700);
FORCEPROP 1 LAST HDL_POWER GND
J 0
(-8450 3850);
PAINT GREEN (-8450 3850);
DISPLAY INVISIBLE (-8450 3850);
FORCEPROP 1 LAST BODY_TYPE PLUMBING
J 0
(-8495 3657);
DISPLAY 0.340426 (-8495 3657);
PAINT GREEN (-8495 3657);
DISPLAY INVISIBLE (-8495 3657);
FORCEPROP 1 LAST SIZE 1B
J 0
(-8375 3650);
DISPLAY 2.382979 (-8375 3650);
PAINT GREEN (-8375 3650);
DISPLAY INVISIBLE (-8375 3650);
FORCEPROP 1 LAST VOLTAGE 0.0V
J 0
(-8495 3657);
DISPLAY 0.340426 (-8495 3657);
PAINT SKYBLUE (-8495 3657);
DISPLAY INVISIBLE (-8495 3657);
FORCEADD TEST-PAD-12P-1-GP-U..1
(-8825 4075);
FORCEPROP 2 LASTPIN (-8600 3900) $PN 10
J 0
(-8590 3910);
DISPLAY 0.808511 (-8590 3910);
PAINT ORANGE (-8590 3910);
FORCEPROP 1 LAST VALUE TEST-PAD-12P-1-GP-U
J 0
(-8900 3650);
DISPLAY 0.617021 (-8900 3650);
PAINT GREEN (-8900 3650);
FORCEPROP 2 LASTPIN (-8600 4250) $PN 3
J 0
(-8590 4260);
DISPLAY 0.808511 (-8590 4260);
PAINT ORANGE (-8590 4260);
FORCEPROP 2 LASTPIN (-8600 4200) $PN 4
J 0
(-8590 4210);
DISPLAY 0.808511 (-8590 4210);
PAINT ORANGE (-8590 4210);
FORCEPROP 2 LASTPIN (-8600 4150) $PN 5
J 0
(-8590 4160);
DISPLAY 0.808511 (-8590 4160);
PAINT ORANGE (-8590 4160);
FORCEPROP 2 LASTPIN (-8600 4100) $PN 6
J 0
(-8590 4110);
DISPLAY 0.808511 (-8590 4110);
PAINT ORANGE (-8590 4110);
FORCEPROP 2 LASTPIN (-8600 4050) $PN 7
J 0
(-8590 4060);
DISPLAY 0.808511 (-8590 4060);
PAINT ORANGE (-8590 4060);
FORCEPROP 2 LASTPIN (-8600 4000) $PN 8
J 0
(-8590 4010);
DISPLAY 0.808511 (-8590 4010);
PAINT ORANGE (-8590 4010);
FORCEPROP 2 LASTPIN (-8600 3950) $PN 9
J 0
(-8590 3960);
DISPLAY 0.808511 (-8590 3960);
PAINT ORANGE (-8590 3960);
FORCEPROP 2 LASTPIN (-8600 4350) $PN 1
J 0
(-8590 4360);
DISPLAY 0.808511 (-8590 4360);
PAINT ORANGE (-8590 4360);
FORCEPROP 2 LASTPIN (-8600 4300) $PN 2
J 0
(-8590 4310);
DISPLAY 0.808511 (-8590 4310);
PAINT ORANGE (-8590 4310);
FORCEPROP 1 LAST LOCATION T1D5
J 0
(-8800 4475);
DISPLAY 0.617021 (-8800 4475);
PAINT GREEN (-8800 4475);
FORCEPROP 2 LASTPIN (-8600 3800) $PN 12
J 0
(-8590 3810);
DISPLAY 0.808511 (-8590 3810);
PAINT ORANGE (-8590 3810);
FORCEPROP 2 LASTPIN (-8600 3850) $PN 11
J 0
(-8590 3860);
DISPLAY 0.808511 (-8590 3860);
PAINT ORANGE (-8590 3860);
FORCEPROP 1 LAST PATH I12
J 0
(-8825 4365);
DISPLAY 0.617021 (-8825 4365);
PAINT GREEN (-8825 4365);
DISPLAY INVISIBLE (-8825 4365);
FORCEPROP 2 LAST SEC_TYPE DISCRET-GB1
J 0
(-8800 4525);
DISPLAY 1.021277 (-8800 4525);
PAINT ORANGE (-8800 4525);
DISPLAY INVISIBLE (-8800 4525);
FORCEPROP 2 LAST SEC 1
J 0
(-8800 4525);
DISPLAY 0.680851 (-8800 4525);
PAINT MONO (-8800 4525);
DISPLAY INVISIBLE (-8800 4525);
FORCEPROP 1 LAST PACK_TYPE DISCRET-GB1
J 0
(-8825 4075);
DISPLAY 0.617021 (-8825 4075);
PAINT GREEN (-8825 4075);
DISPLAY INVISIBLE (-8825 4075);
FORCEPROP 1 LAST PART_NUMBER ZZ.00PAD.MJ1
J 0
(-8825 3786);
DISPLAY 0.617021 (-8825 3786);
PAINT GREEN (-8825 3786);
DISPLAY INVISIBLE (-8825 3786);
FORCEPROP 2 LAST CDS_LIB w_hdl
J 0
(-8825 4075);
DISPLAY INVISIBLE (-8825 4075);
FORCEPROP 1 LAST CDS_LMAN_SYM_OUTLINE -75,375,75,-375
J 0
(-8825 4075);
DISPLAY 0.468085 (-8825 4075);
PAINT GREEN (-8825 4075);
DISPLAY INVISIBLE (-8825 4075);
FORCEADD TEST-PAD-12P-1-GP-U..1
R 2
(-4775 6000);
FORCEPROP 1 LAST LOCATION T1D8
J 2
(-4800 6400);
DISPLAY 0.617021 (-4800 6400);
PAINT GREEN (-4800 6400);
FORCEPROP 1 LAST VALUE TEST-PAD-12P-1-GP-U
J 2
(-4700 5575);
DISPLAY 0.617021 (-4700 5575);
PAINT GREEN (-4700 5575);
FORCEPROP 2 LASTPIN (-5000 6225) $PN 2
J 2
(-5010 6235);
DISPLAY 0.808511 (-5010 6235);
PAINT ORANGE (-5010 6235);
FORCEPROP 2 LASTPIN (-5000 6275) $PN 1
J 2
(-5010 6285);
DISPLAY 0.808511 (-5010 6285);
PAINT ORANGE (-5010 6285);
FORCEPROP 2 LASTPIN (-5000 5725) $PN 12
J 2
(-5010 5735);
DISPLAY 0.808511 (-5010 5735);
PAINT ORANGE (-5010 5735);
FORCEPROP 2 LASTPIN (-5000 5775) $PN 11
J 2
(-5010 5785);
DISPLAY 0.808511 (-5010 5785);
PAINT ORANGE (-5010 5785);
FORCEPROP 2 LASTPIN (-5000 5825) $PN 10
J 2
(-5010 5835);
DISPLAY 0.808511 (-5010 5835);
PAINT ORANGE (-5010 5835);
FORCEPROP 2 LASTPIN (-5000 5875) $PN 9
J 2
(-5010 5885);
DISPLAY 0.808511 (-5010 5885);
PAINT ORANGE (-5010 5885);
FORCEPROP 2 LASTPIN (-5000 5925) $PN 8
J 2
(-5010 5935);
DISPLAY 0.808511 (-5010 5935);
PAINT ORANGE (-5010 5935);
FORCEPROP 2 LASTPIN (-5000 5975) $PN 7
J 2
(-5010 5985);
DISPLAY 0.808511 (-5010 5985);
PAINT ORANGE (-5010 5985);
FORCEPROP 2 LASTPIN (-5000 6025) $PN 6
J 2
(-5010 6035);
DISPLAY 0.808511 (-5010 6035);
PAINT ORANGE (-5010 6035);
FORCEPROP 2 LASTPIN (-5000 6075) $PN 5
J 2
(-5010 6085);
DISPLAY 0.808511 (-5010 6085);
PAINT ORANGE (-5010 6085);
FORCEPROP 2 LASTPIN (-5000 6125) $PN 4
J 2
(-5010 6135);
DISPLAY 0.808511 (-5010 6135);
PAINT ORANGE (-5010 6135);
FORCEPROP 2 LASTPIN (-5000 6175) $PN 3
J 2
(-5010 6185);
DISPLAY 0.808511 (-5010 6185);
PAINT ORANGE (-5010 6185);
FORCEPROP 1 LAST CDS_LMAN_SYM_OUTLINE -75,375,75,-375
J 2
(-4775 6000);
DISPLAY 0.468085 (-4775 6000);
PAINT GREEN (-4775 6000);
DISPLAY INVISIBLE (-4775 6000);
FORCEPROP 2 LAST CDS_LIB w_hdl
J 2
(-4775 6000);
DISPLAY INVISIBLE (-4775 6000);
FORCEPROP 1 LAST PART_NUMBER ZZ.00PAD.MJ1
J 2
(-4775 5711);
DISPLAY 0.617021 (-4775 5711);
PAINT GREEN (-4775 5711);
DISPLAY INVISIBLE (-4775 5711);
FORCEPROP 1 LAST PACK_TYPE DISCRET-GB1
J 2
(-4775 6000);
DISPLAY 0.617021 (-4775 6000);
PAINT GREEN (-4775 6000);
DISPLAY INVISIBLE (-4775 6000);
FORCEPROP 2 LAST SEC 1
J 2
(-4800 6450);
DISPLAY 0.680851 (-4800 6450);
PAINT MONO (-4800 6450);
DISPLAY INVISIBLE (-4800 6450);
FORCEPROP 2 LAST SEC_TYPE DISCRET-GB1
J 2
(-4800 6450);
DISPLAY 1.021277 (-4800 6450);
PAINT ORANGE (-4800 6450);
DISPLAY INVISIBLE (-4800 6450);
FORCEPROP 1 LAST PATH I13
J 2
(-4775 6290);
DISPLAY 0.617021 (-4775 6290);
PAINT GREEN (-4775 6290);
DISPLAY INVISIBLE (-4775 6290);
FORCEADD GND..1
(-5150 5625);
FORCEPROP 3 LASTPIN (-5150 5675) SIG_NAME GND\g
J 0
(-5140 5685);
DISPLAY 0.659574 (-5140 5685);
PAINT MONO (-5140 5685);
DISPLAY INVISIBLE (-5140 5685);
FORCEPROP 2 LAST CDS_LIB mstr_symbols
J 0
(-5150 5625);
DISPLAY INVISIBLE (-5150 5625);
FORCEPROP 1 LAST HDL_POWER GND
J 0
(-5150 5775);
PAINT GREEN (-5150 5775);
DISPLAY INVISIBLE (-5150 5775);
FORCEPROP 1 LAST BODY_TYPE PLUMBING
J 0
(-5195 5582);
DISPLAY 0.340426 (-5195 5582);
PAINT GREEN (-5195 5582);
DISPLAY INVISIBLE (-5195 5582);
FORCEPROP 1 LAST SIZE 1B
J 0
(-5075 5575);
DISPLAY 2.382979 (-5075 5575);
PAINT GREEN (-5075 5575);
DISPLAY INVISIBLE (-5075 5575);
FORCEPROP 1 LAST VOLTAGE 0.0V
J 0
(-5195 5582);
DISPLAY 0.340426 (-5195 5582);
PAINT SKYBLUE (-5195 5582);
DISPLAY INVISIBLE (-5195 5582);
FORCEPROP 1 LAST PATH I14
J 0
(-5075 5625);
DISPLAY 0.872340 (-5075 5625);
PAINT AQUA (-5075 5625);
DISPLAY INVISIBLE (-5075 5625);
FORCEADD GND..1
(-6000 5625);
FORCEPROP 3 LASTPIN (-6000 5675) SIG_NAME GND\g
J 0
(-5990 5685);
DISPLAY 0.659574 (-5990 5685);
PAINT MONO (-5990 5685);
DISPLAY INVISIBLE (-5990 5685);
FORCEPROP 1 LAST VOLTAGE 0.0V
J 0
(-6045 5582);
DISPLAY 0.340426 (-6045 5582);
PAINT SKYBLUE (-6045 5582);
DISPLAY INVISIBLE (-6045 5582);
FORCEPROP 1 LAST SIZE 1B
J 0
(-5925 5575);
DISPLAY 2.382979 (-5925 5575);
PAINT GREEN (-5925 5575);
DISPLAY INVISIBLE (-5925 5575);
FORCEPROP 1 LAST BODY_TYPE PLUMBING
J 0
(-6045 5582);
DISPLAY 0.340426 (-6045 5582);
PAINT GREEN (-6045 5582);
DISPLAY INVISIBLE (-6045 5582);
FORCEPROP 1 LAST HDL_POWER GND
J 0
(-6000 5775);
PAINT GREEN (-6000 5775);
DISPLAY INVISIBLE (-6000 5775);
FORCEPROP 2 LAST CDS_LIB mstr_symbols
J 0
(-6000 5625);
DISPLAY INVISIBLE (-6000 5625);
FORCEPROP 1 LAST PATH I15
J 0
(-5925 5625);
DISPLAY 0.872340 (-5925 5625);
PAINT AQUA (-5925 5625);
DISPLAY INVISIBLE (-5925 5625);
FORCEADD TEST-PAD-12P-1-GP-U..1
(-6375 6000);
FORCEPROP 1 LAST VALUE TEST-PAD-12P-1-GP-U
J 0
(-6450 5575);
DISPLAY 0.617021 (-6450 5575);
PAINT GREEN (-6450 5575);
FORCEPROP 1 LAST LOCATION T1D7
J 0
(-6350 6400);
DISPLAY 0.617021 (-6350 6400);
PAINT GREEN (-6350 6400);
FORCEPROP 2 LASTPIN (-6150 6225) $PN 2
J 0
(-6140 6235);
DISPLAY 0.808511 (-6140 6235);
PAINT ORANGE (-6140 6235);
FORCEPROP 2 LASTPIN (-6150 6275) $PN 1
J 0
(-6140 6285);
DISPLAY 0.808511 (-6140 6285);
PAINT ORANGE (-6140 6285);
FORCEPROP 2 LASTPIN (-6150 5725) $PN 12
J 0
(-6140 5735);
DISPLAY 0.808511 (-6140 5735);
PAINT ORANGE (-6140 5735);
FORCEPROP 2 LASTPIN (-6150 5775) $PN 11
J 0
(-6140 5785);
DISPLAY 0.808511 (-6140 5785);
PAINT ORANGE (-6140 5785);
FORCEPROP 2 LASTPIN (-6150 5825) $PN 10
J 0
(-6140 5835);
DISPLAY 0.808511 (-6140 5835);
PAINT ORANGE (-6140 5835);
FORCEPROP 2 LASTPIN (-6150 5875) $PN 9
J 0
(-6140 5885);
DISPLAY 0.808511 (-6140 5885);
PAINT ORANGE (-6140 5885);
FORCEPROP 2 LASTPIN (-6150 5925) $PN 8
J 0
(-6140 5935);
DISPLAY 0.808511 (-6140 5935);
PAINT ORANGE (-6140 5935);
FORCEPROP 2 LASTPIN (-6150 5975) $PN 7
J 0
(-6140 5985);
DISPLAY 0.808511 (-6140 5985);
PAINT ORANGE (-6140 5985);
FORCEPROP 2 LASTPIN (-6150 6025) $PN 6
J 0
(-6140 6035);
DISPLAY 0.808511 (-6140 6035);
PAINT ORANGE (-6140 6035);
FORCEPROP 2 LASTPIN (-6150 6075) $PN 5
J 0
(-6140 6085);
DISPLAY 0.808511 (-6140 6085);
PAINT ORANGE (-6140 6085);
FORCEPROP 2 LASTPIN (-6150 6125) $PN 4
J 0
(-6140 6135);
DISPLAY 0.808511 (-6140 6135);
PAINT ORANGE (-6140 6135);
FORCEPROP 2 LASTPIN (-6150 6175) $PN 3
J 0
(-6140 6185);
DISPLAY 0.808511 (-6140 6185);
PAINT ORANGE (-6140 6185);
FORCEPROP 1 LAST CDS_LMAN_SYM_OUTLINE -75,375,75,-375
J 0
(-6375 6000);
DISPLAY 0.468085 (-6375 6000);
PAINT GREEN (-6375 6000);
DISPLAY INVISIBLE (-6375 6000);
FORCEPROP 2 LAST CDS_LIB w_hdl
J 0
(-6375 6000);
DISPLAY INVISIBLE (-6375 6000);
FORCEPROP 1 LAST PART_NUMBER ZZ.00PAD.MJ1
J 0
(-6375 5711);
DISPLAY 0.617021 (-6375 5711);
PAINT GREEN (-6375 5711);
DISPLAY INVISIBLE (-6375 5711);
FORCEPROP 1 LAST PACK_TYPE DISCRET-GB1
J 0
(-6375 6000);
DISPLAY 0.617021 (-6375 6000);
PAINT GREEN (-6375 6000);
DISPLAY INVISIBLE (-6375 6000);
FORCEPROP 2 LAST SEC 1
J 0
(-6350 6450);
DISPLAY 0.680851 (-6350 6450);
PAINT MONO (-6350 6450);
DISPLAY INVISIBLE (-6350 6450);
FORCEPROP 2 LAST SEC_TYPE DISCRET-GB1
J 0
(-6350 6450);
DISPLAY 1.021277 (-6350 6450);
PAINT ORANGE (-6350 6450);
DISPLAY INVISIBLE (-6350 6450);
FORCEPROP 1 LAST PATH I16
J 0
(-6375 6290);
DISPLAY 0.617021 (-6375 6290);
PAINT GREEN (-6375 6290);
DISPLAY INVISIBLE (-6375 6290);
FORCEADD TEST-PAD-12P-1-GP-U..1
R 2
(-4775 5050);
FORCEPROP 2 LASTPIN (-5000 5225) $PN 3
J 2
(-5010 5235);
DISPLAY 0.808511 (-5010 5235);
PAINT ORANGE (-5010 5235);
FORCEPROP 2 LASTPIN (-5000 5125) $PN 5
J 2
(-5010 5135);
DISPLAY 0.808511 (-5010 5135);
PAINT ORANGE (-5010 5135);
FORCEPROP 2 LASTPIN (-5000 5075) $PN 6
J 2
(-5010 5085);
DISPLAY 0.808511 (-5010 5085);
PAINT ORANGE (-5010 5085);
FORCEPROP 2 LASTPIN (-5000 5025) $PN 7
J 2
(-5010 5035);
DISPLAY 0.808511 (-5010 5035);
PAINT ORANGE (-5010 5035);
FORCEPROP 2 LASTPIN (-5000 4975) $PN 8
J 2
(-5010 4985);
DISPLAY 0.808511 (-5010 4985);
PAINT ORANGE (-5010 4985);
FORCEPROP 2 LASTPIN (-5000 4925) $PN 9
J 2
(-5010 4935);
DISPLAY 0.808511 (-5010 4935);
PAINT ORANGE (-5010 4935);
FORCEPROP 2 LASTPIN (-5000 4775) $PN 12
J 2
(-5010 4785);
DISPLAY 0.808511 (-5010 4785);
PAINT ORANGE (-5010 4785);
FORCEPROP 2 LASTPIN (-5000 5325) $PN 1
J 2
(-5010 5335);
DISPLAY 0.808511 (-5010 5335);
PAINT ORANGE (-5010 5335);
FORCEPROP 2 LASTPIN (-5000 5275) $PN 2
J 2
(-5010 5285);
DISPLAY 0.808511 (-5010 5285);
PAINT ORANGE (-5010 5285);
FORCEPROP 1 LAST LOCATION T1D10
J 2
(-4800 5450);
DISPLAY 0.617021 (-4800 5450);
PAINT GREEN (-4800 5450);
FORCEPROP 2 LASTPIN (-5000 5175) $PN 4
J 2
(-5010 5185);
DISPLAY 0.808511 (-5010 5185);
PAINT ORANGE (-5010 5185);
FORCEPROP 2 LASTPIN (-5000 4875) $PN 10
J 2
(-5010 4885);
DISPLAY 0.808511 (-5010 4885);
PAINT ORANGE (-5010 4885);
FORCEPROP 2 LASTPIN (-5000 4825) $PN 11
J 2
(-5010 4835);
DISPLAY 0.808511 (-5010 4835);
PAINT ORANGE (-5010 4835);
FORCEPROP 1 LAST VALUE TEST-PAD-12P-1-GP-U
J 2
(-4700 4625);
DISPLAY 0.617021 (-4700 4625);
PAINT GREEN (-4700 4625);
FORCEPROP 1 LAST PATH I17
J 2
(-4775 5340);
DISPLAY 0.617021 (-4775 5340);
PAINT GREEN (-4775 5340);
DISPLAY INVISIBLE (-4775 5340);
FORCEPROP 2 LAST SEC_TYPE DISCRET-GB1
J 2
(-4800 5500);
DISPLAY 1.021277 (-4800 5500);
PAINT ORANGE (-4800 5500);
DISPLAY INVISIBLE (-4800 5500);
FORCEPROP 2 LAST SEC 1
J 2
(-4800 5500);
DISPLAY 0.680851 (-4800 5500);
PAINT MONO (-4800 5500);
DISPLAY INVISIBLE (-4800 5500);
FORCEPROP 1 LAST PACK_TYPE DISCRET-GB1
J 2
(-4775 5050);
DISPLAY 0.617021 (-4775 5050);
PAINT GREEN (-4775 5050);
DISPLAY INVISIBLE (-4775 5050);
FORCEPROP 1 LAST PART_NUMBER ZZ.00PAD.MJ1
J 2
(-4775 4761);
DISPLAY 0.617021 (-4775 4761);
PAINT GREEN (-4775 4761);
DISPLAY INVISIBLE (-4775 4761);
FORCEPROP 2 LAST CDS_LIB w_hdl
J 2
(-4775 5050);
DISPLAY INVISIBLE (-4775 5050);
FORCEPROP 1 LAST CDS_LMAN_SYM_OUTLINE -75,375,75,-375
J 2
(-4775 5050);
DISPLAY 0.468085 (-4775 5050);
PAINT GREEN (-4775 5050);
DISPLAY INVISIBLE (-4775 5050);
FORCEADD TEST-PAD-12P-1-GP-U..1
(-6375 5050);
FORCEPROP 2 LASTPIN (-6150 5225) $PN 3
J 0
(-6140 5235);
DISPLAY 0.808511 (-6140 5235);
PAINT ORANGE (-6140 5235);
FORCEPROP 2 LASTPIN (-6150 5175) $PN 4
J 0
(-6140 5185);
DISPLAY 0.808511 (-6140 5185);
PAINT ORANGE (-6140 5185);
FORCEPROP 2 LASTPIN (-6150 5125) $PN 5
J 0
(-6140 5135);
DISPLAY 0.808511 (-6140 5135);
PAINT ORANGE (-6140 5135);
FORCEPROP 2 LASTPIN (-6150 5075) $PN 6
J 0
(-6140 5085);
DISPLAY 0.808511 (-6140 5085);
PAINT ORANGE (-6140 5085);
FORCEPROP 2 LASTPIN (-6150 5025) $PN 7
J 0
(-6140 5035);
DISPLAY 0.808511 (-6140 5035);
PAINT ORANGE (-6140 5035);
FORCEPROP 2 LASTPIN (-6150 4975) $PN 8
J 0
(-6140 4985);
DISPLAY 0.808511 (-6140 4985);
PAINT ORANGE (-6140 4985);
FORCEPROP 2 LASTPIN (-6150 4925) $PN 9
J 0
(-6140 4935);
DISPLAY 0.808511 (-6140 4935);
PAINT ORANGE (-6140 4935);
FORCEPROP 2 LASTPIN (-6150 4875) $PN 10
J 0
(-6140 4885);
DISPLAY 0.808511 (-6140 4885);
PAINT ORANGE (-6140 4885);
FORCEPROP 2 LASTPIN (-6150 4825) $PN 11
J 0
(-6140 4835);
DISPLAY 0.808511 (-6140 4835);
PAINT ORANGE (-6140 4835);
FORCEPROP 2 LASTPIN (-6150 4775) $PN 12
J 0
(-6140 4785);
DISPLAY 0.808511 (-6140 4785);
PAINT ORANGE (-6140 4785);
FORCEPROP 2 LASTPIN (-6150 5325) $PN 1
J 0
(-6140 5335);
DISPLAY 0.808511 (-6140 5335);
PAINT ORANGE (-6140 5335);
FORCEPROP 2 LASTPIN (-6150 5275) $PN 2
J 0
(-6140 5285);
DISPLAY 0.808511 (-6140 5285);
PAINT ORANGE (-6140 5285);
FORCEPROP 1 LAST VALUE TEST-PAD-12P-1-GP-U
J 0
(-6450 4625);
DISPLAY 0.617021 (-6450 4625);
PAINT GREEN (-6450 4625);
FORCEPROP 1 LAST LOCATION T1D9
J 0
(-6350 5450);
DISPLAY 0.617021 (-6350 5450);
PAINT GREEN (-6350 5450);
FORCEPROP 1 LAST PATH I18
J 0
(-6375 5340);
DISPLAY 0.617021 (-6375 5340);
PAINT GREEN (-6375 5340);
DISPLAY INVISIBLE (-6375 5340);
FORCEPROP 2 LAST SEC_TYPE DISCRET-GB1
J 0
(-6350 5500);
DISPLAY 1.021277 (-6350 5500);
PAINT ORANGE (-6350 5500);
DISPLAY INVISIBLE (-6350 5500);
FORCEPROP 2 LAST SEC 1
J 0
(-6350 5500);
DISPLAY 0.680851 (-6350 5500);
PAINT MONO (-6350 5500);
DISPLAY INVISIBLE (-6350 5500);
FORCEPROP 1 LAST PACK_TYPE DISCRET-GB1
J 0
(-6375 5050);
DISPLAY 0.617021 (-6375 5050);
PAINT GREEN (-6375 5050);
DISPLAY INVISIBLE (-6375 5050);
FORCEPROP 1 LAST PART_NUMBER ZZ.00PAD.MJ1
J 0
(-6375 4761);
DISPLAY 0.617021 (-6375 4761);
PAINT GREEN (-6375 4761);
DISPLAY INVISIBLE (-6375 4761);
FORCEPROP 2 LAST CDS_LIB w_hdl
J 0
(-6375 5050);
DISPLAY INVISIBLE (-6375 5050);
FORCEPROP 1 LAST CDS_LMAN_SYM_OUTLINE -75,375,75,-375
J 0
(-6375 5050);
DISPLAY 0.468085 (-6375 5050);
PAINT GREEN (-6375 5050);
DISPLAY INVISIBLE (-6375 5050);
FORCEADD GND..1
(-5150 4675);
FORCEPROP 3 LASTPIN (-5150 4725) SIG_NAME GND\g
J 0
(-5140 4735);
DISPLAY 0.659574 (-5140 4735);
PAINT MONO (-5140 4735);
DISPLAY INVISIBLE (-5140 4735);
FORCEPROP 1 LAST PATH I19
J 0
(-5075 4675);
DISPLAY 0.872340 (-5075 4675);
PAINT AQUA (-5075 4675);
DISPLAY INVISIBLE (-5075 4675);
FORCEPROP 1 LAST VOLTAGE 0.0V
J 0
(-5195 4632);
DISPLAY 0.340426 (-5195 4632);
PAINT SKYBLUE (-5195 4632);
DISPLAY INVISIBLE (-5195 4632);
FORCEPROP 1 LAST SIZE 1B
J 0
(-5075 4625);
DISPLAY 2.382979 (-5075 4625);
PAINT GREEN (-5075 4625);
DISPLAY INVISIBLE (-5075 4625);
FORCEPROP 1 LAST BODY_TYPE PLUMBING
J 0
(-5195 4632);
DISPLAY 0.340426 (-5195 4632);
PAINT GREEN (-5195 4632);
DISPLAY INVISIBLE (-5195 4632);
FORCEPROP 1 LAST HDL_POWER GND
J 0
(-5150 4825);
PAINT GREEN (-5150 4825);
DISPLAY INVISIBLE (-5150 4825);
FORCEPROP 2 LAST CDS_LIB mstr_symbols
J 0
(-5150 4675);
DISPLAY INVISIBLE (-5150 4675);
FORCEADD GND..1
(-8450 5600);
FORCEPROP 3 LASTPIN (-8450 5650) SIG_NAME GND\g
J 0
(-8440 5660);
DISPLAY 0.659574 (-8440 5660);
PAINT MONO (-8440 5660);
DISPLAY INVISIBLE (-8440 5660);
FORCEPROP 1 LAST VOLTAGE 0.0V
J 0
(-8495 5557);
DISPLAY 0.340426 (-8495 5557);
PAINT SKYBLUE (-8495 5557);
DISPLAY INVISIBLE (-8495 5557);
FORCEPROP 1 LAST SIZE 1B
J 0
(-8375 5550);
DISPLAY 2.382979 (-8375 5550);
PAINT GREEN (-8375 5550);
DISPLAY INVISIBLE (-8375 5550);
FORCEPROP 1 LAST BODY_TYPE PLUMBING
J 0
(-8495 5557);
DISPLAY 0.340426 (-8495 5557);
PAINT GREEN (-8495 5557);
DISPLAY INVISIBLE (-8495 5557);
FORCEPROP 1 LAST HDL_POWER GND
J 0
(-8450 5750);
PAINT GREEN (-8450 5750);
DISPLAY INVISIBLE (-8450 5750);
FORCEPROP 1 LAST PATH I2
J 0
(-8375 5600);
DISPLAY 0.872340 (-8375 5600);
PAINT AQUA (-8375 5600);
DISPLAY INVISIBLE (-8375 5600);
FORCEPROP 2 LAST CDS_LIB mstr_symbols
J 0
(-8450 5600);
DISPLAY INVISIBLE (-8450 5600);
FORCEADD GND..1
(-6000 4675);
FORCEPROP 3 LASTPIN (-6000 4725) SIG_NAME GND\g
J 0
(-5990 4735);
DISPLAY 0.659574 (-5990 4735);
PAINT MONO (-5990 4735);
DISPLAY INVISIBLE (-5990 4735);
FORCEPROP 1 LAST PATH I20
J 0
(-5925 4675);
DISPLAY 0.872340 (-5925 4675);
PAINT AQUA (-5925 4675);
DISPLAY INVISIBLE (-5925 4675);
FORCEPROP 2 LAST CDS_LIB mstr_symbols
J 0
(-6000 4675);
DISPLAY INVISIBLE (-6000 4675);
FORCEPROP 1 LAST HDL_POWER GND
J 0
(-6000 4825);
PAINT GREEN (-6000 4825);
DISPLAY INVISIBLE (-6000 4825);
FORCEPROP 1 LAST BODY_TYPE PLUMBING
J 0
(-6045 4632);
DISPLAY 0.340426 (-6045 4632);
PAINT GREEN (-6045 4632);
DISPLAY INVISIBLE (-6045 4632);
FORCEPROP 1 LAST SIZE 1B
J 0
(-5925 4625);
DISPLAY 2.382979 (-5925 4625);
PAINT GREEN (-5925 4625);
DISPLAY INVISIBLE (-5925 4625);
FORCEPROP 1 LAST VOLTAGE 0.0V
J 0
(-6045 4632);
DISPLAY 0.340426 (-6045 4632);
PAINT SKYBLUE (-6045 4632);
DISPLAY INVISIBLE (-6045 4632);
FORCEADD TEST-PAD-12P-1-GP-U..1
R 2
(-4775 4100);
FORCEPROP 1 LAST VALUE TEST-PAD-12P-1-GP-U
J 2
(-4700 3675);
DISPLAY 0.617021 (-4700 3675);
PAINT GREEN (-4700 3675);
FORCEPROP 2 LASTPIN (-5000 4325) $PN 2
J 2
(-5010 4335);
DISPLAY 0.808511 (-5010 4335);
PAINT ORANGE (-5010 4335);
FORCEPROP 2 LASTPIN (-5000 4375) $PN 1
J 2
(-5010 4385);
DISPLAY 0.808511 (-5010 4385);
PAINT ORANGE (-5010 4385);
FORCEPROP 2 LASTPIN (-5000 3825) $PN 12
J 2
(-5010 3835);
DISPLAY 0.808511 (-5010 3835);
PAINT ORANGE (-5010 3835);
FORCEPROP 2 LASTPIN (-5000 3875) $PN 11
J 2
(-5010 3885);
DISPLAY 0.808511 (-5010 3885);
PAINT ORANGE (-5010 3885);
FORCEPROP 2 LASTPIN (-5000 3925) $PN 10
J 2
(-5010 3935);
DISPLAY 0.808511 (-5010 3935);
PAINT ORANGE (-5010 3935);
FORCEPROP 2 LASTPIN (-5000 3975) $PN 9
J 2
(-5010 3985);
DISPLAY 0.808511 (-5010 3985);
PAINT ORANGE (-5010 3985);
FORCEPROP 2 LASTPIN (-5000 4025) $PN 8
J 2
(-5010 4035);
DISPLAY 0.808511 (-5010 4035);
PAINT ORANGE (-5010 4035);
FORCEPROP 2 LASTPIN (-5000 4075) $PN 7
J 2
(-5010 4085);
DISPLAY 0.808511 (-5010 4085);
PAINT ORANGE (-5010 4085);
FORCEPROP 2 LASTPIN (-5000 4125) $PN 6
J 2
(-5010 4135);
DISPLAY 0.808511 (-5010 4135);
PAINT ORANGE (-5010 4135);
FORCEPROP 2 LASTPIN (-5000 4175) $PN 5
J 2
(-5010 4185);
DISPLAY 0.808511 (-5010 4185);
PAINT ORANGE (-5010 4185);
FORCEPROP 2 LASTPIN (-5000 4225) $PN 4
J 2
(-5010 4235);
DISPLAY 0.808511 (-5010 4235);
PAINT ORANGE (-5010 4235);
FORCEPROP 2 LASTPIN (-5000 4275) $PN 3
J 2
(-5010 4285);
DISPLAY 0.808511 (-5010 4285);
PAINT ORANGE (-5010 4285);
FORCEPROP 1 LAST LOCATION T1D12
J 2
(-4800 4500);
DISPLAY 0.617021 (-4800 4500);
PAINT GREEN (-4800 4500);
FORCEPROP 1 LAST CDS_LMAN_SYM_OUTLINE -75,375,75,-375
J 2
(-4775 4100);
DISPLAY 0.468085 (-4775 4100);
PAINT GREEN (-4775 4100);
DISPLAY INVISIBLE (-4775 4100);
FORCEPROP 2 LAST CDS_LIB w_hdl
J 2
(-4775 4100);
DISPLAY INVISIBLE (-4775 4100);
FORCEPROP 1 LAST PART_NUMBER ZZ.00PAD.MJ1
J 2
(-4775 3811);
DISPLAY 0.617021 (-4775 3811);
PAINT GREEN (-4775 3811);
DISPLAY INVISIBLE (-4775 3811);
FORCEPROP 1 LAST PACK_TYPE DISCRET-GB1
J 2
(-4775 4100);
DISPLAY 0.617021 (-4775 4100);
PAINT GREEN (-4775 4100);
DISPLAY INVISIBLE (-4775 4100);
FORCEPROP 2 LAST SEC 1
J 2
(-4800 4550);
DISPLAY 0.680851 (-4800 4550);
PAINT MONO (-4800 4550);
DISPLAY INVISIBLE (-4800 4550);
FORCEPROP 2 LAST SEC_TYPE DISCRET-GB1
J 2
(-4800 4550);
DISPLAY 1.021277 (-4800 4550);
PAINT ORANGE (-4800 4550);
DISPLAY INVISIBLE (-4800 4550);
FORCEPROP 1 LAST PATH I21
J 2
(-4775 4390);
DISPLAY 0.617021 (-4775 4390);
PAINT GREEN (-4775 4390);
DISPLAY INVISIBLE (-4775 4390);
FORCEADD GND..1
(-5150 3725);
FORCEPROP 3 LASTPIN (-5150 3775) SIG_NAME GND\g
J 0
(-5140 3785);
DISPLAY 0.659574 (-5140 3785);
PAINT MONO (-5140 3785);
DISPLAY INVISIBLE (-5140 3785);
FORCEPROP 2 LAST CDS_LIB mstr_symbols
J 0
(-5150 3725);
DISPLAY INVISIBLE (-5150 3725);
FORCEPROP 1 LAST HDL_POWER GND
J 0
(-5150 3875);
PAINT GREEN (-5150 3875);
DISPLAY INVISIBLE (-5150 3875);
FORCEPROP 1 LAST BODY_TYPE PLUMBING
J 0
(-5195 3682);
DISPLAY 0.340426 (-5195 3682);
PAINT GREEN (-5195 3682);
DISPLAY INVISIBLE (-5195 3682);
FORCEPROP 1 LAST SIZE 1B
J 0
(-5075 3675);
DISPLAY 2.382979 (-5075 3675);
PAINT GREEN (-5075 3675);
DISPLAY INVISIBLE (-5075 3675);
FORCEPROP 1 LAST VOLTAGE 0.0V
J 0
(-5195 3682);
DISPLAY 0.340426 (-5195 3682);
PAINT SKYBLUE (-5195 3682);
DISPLAY INVISIBLE (-5195 3682);
FORCEPROP 1 LAST PATH I22
J 0
(-5075 3725);
DISPLAY 0.872340 (-5075 3725);
PAINT AQUA (-5075 3725);
DISPLAY INVISIBLE (-5075 3725);
FORCEADD GND..1
(-6000 3725);
FORCEPROP 3 LASTPIN (-6000 3775) SIG_NAME GND\g
J 0
(-5990 3785);
DISPLAY 0.659574 (-5990 3785);
PAINT MONO (-5990 3785);
DISPLAY INVISIBLE (-5990 3785);
FORCEPROP 1 LAST VOLTAGE 0.0V
J 0
(-6045 3682);
DISPLAY 0.340426 (-6045 3682);
PAINT SKYBLUE (-6045 3682);
DISPLAY INVISIBLE (-6045 3682);
FORCEPROP 1 LAST SIZE 1B
J 0
(-5925 3675);
DISPLAY 2.382979 (-5925 3675);
PAINT GREEN (-5925 3675);
DISPLAY INVISIBLE (-5925 3675);
FORCEPROP 1 LAST BODY_TYPE PLUMBING
J 0
(-6045 3682);
DISPLAY 0.340426 (-6045 3682);
PAINT GREEN (-6045 3682);
DISPLAY INVISIBLE (-6045 3682);
FORCEPROP 1 LAST HDL_POWER GND
J 0
(-6000 3875);
PAINT GREEN (-6000 3875);
DISPLAY INVISIBLE (-6000 3875);
FORCEPROP 2 LAST CDS_LIB mstr_symbols
J 0
(-6000 3725);
DISPLAY INVISIBLE (-6000 3725);
FORCEPROP 1 LAST PATH I23
J 0
(-5925 3725);
DISPLAY 0.872340 (-5925 3725);
PAINT AQUA (-5925 3725);
DISPLAY INVISIBLE (-5925 3725);
FORCEADD TEST-PAD-12P-1-GP-U..1
(-6375 4100);
FORCEPROP 1 LAST VALUE TEST-PAD-12P-1-GP-U
J 0
(-6450 3675);
DISPLAY 0.617021 (-6450 3675);
PAINT GREEN (-6450 3675);
FORCEPROP 2 LASTPIN (-6150 4325) $PN 2
J 0
(-6140 4335);
DISPLAY 0.808511 (-6140 4335);
PAINT ORANGE (-6140 4335);
FORCEPROP 2 LASTPIN (-6150 3825) $PN 12
J 0
(-6140 3835);
DISPLAY 0.808511 (-6140 3835);
PAINT ORANGE (-6140 3835);
FORCEPROP 2 LASTPIN (-6150 3875) $PN 11
J 0
(-6140 3885);
DISPLAY 0.808511 (-6140 3885);
PAINT ORANGE (-6140 3885);
FORCEPROP 2 LASTPIN (-6150 3925) $PN 10
J 0
(-6140 3935);
DISPLAY 0.808511 (-6140 3935);
PAINT ORANGE (-6140 3935);
FORCEPROP 2 LASTPIN (-6150 3975) $PN 9
J 0
(-6140 3985);
DISPLAY 0.808511 (-6140 3985);
PAINT ORANGE (-6140 3985);
FORCEPROP 2 LASTPIN (-6150 4025) $PN 8
J 0
(-6140 4035);
DISPLAY 0.808511 (-6140 4035);
PAINT ORANGE (-6140 4035);
FORCEPROP 2 LASTPIN (-6150 4075) $PN 7
J 0
(-6140 4085);
DISPLAY 0.808511 (-6140 4085);
PAINT ORANGE (-6140 4085);
FORCEPROP 2 LASTPIN (-6150 4125) $PN 6
J 0
(-6140 4135);
DISPLAY 0.808511 (-6140 4135);
PAINT ORANGE (-6140 4135);
FORCEPROP 2 LASTPIN (-6150 4175) $PN 5
J 0
(-6140 4185);
DISPLAY 0.808511 (-6140 4185);
PAINT ORANGE (-6140 4185);
FORCEPROP 2 LASTPIN (-6150 4225) $PN 4
J 0
(-6140 4235);
DISPLAY 0.808511 (-6140 4235);
PAINT ORANGE (-6140 4235);
FORCEPROP 2 LASTPIN (-6150 4275) $PN 3
J 0
(-6140 4285);
DISPLAY 0.808511 (-6140 4285);
PAINT ORANGE (-6140 4285);
FORCEPROP 2 LASTPIN (-6150 4375) $PN 1
J 0
(-6140 4385);
DISPLAY 0.808511 (-6140 4385);
PAINT ORANGE (-6140 4385);
FORCEPROP 1 LAST LOCATION T1D11
J 0
(-6350 4500);
DISPLAY 0.617021 (-6350 4500);
PAINT GREEN (-6350 4500);
FORCEPROP 1 LAST CDS_LMAN_SYM_OUTLINE -75,375,75,-375
J 0
(-6375 4100);
DISPLAY 0.468085 (-6375 4100);
PAINT GREEN (-6375 4100);
DISPLAY INVISIBLE (-6375 4100);
FORCEPROP 2 LAST CDS_LIB w_hdl
J 0
(-6375 4100);
DISPLAY INVISIBLE (-6375 4100);
FORCEPROP 1 LAST PART_NUMBER ZZ.00PAD.MJ1
J 0
(-6375 3811);
DISPLAY 0.617021 (-6375 3811);
PAINT GREEN (-6375 3811);
DISPLAY INVISIBLE (-6375 3811);
FORCEPROP 1 LAST PACK_TYPE DISCRET-GB1
J 0
(-6375 4100);
DISPLAY 0.617021 (-6375 4100);
PAINT GREEN (-6375 4100);
DISPLAY INVISIBLE (-6375 4100);
FORCEPROP 2 LAST SEC 1
J 0
(-6350 4550);
DISPLAY 0.680851 (-6350 4550);
PAINT MONO (-6350 4550);
DISPLAY INVISIBLE (-6350 4550);
FORCEPROP 2 LAST SEC_TYPE DISCRET-GB1
J 0
(-6350 4550);
DISPLAY 1.021277 (-6350 4550);
PAINT ORANGE (-6350 4550);
DISPLAY INVISIBLE (-6350 4550);
FORCEPROP 1 LAST PATH I24
J 0
(-6375 4390);
DISPLAY 0.617021 (-6375 4390);
PAINT GREEN (-6375 4390);
DISPLAY INVISIBLE (-6375 4390);
FORCEADD TEST-PAD-12P-1-GP-U..1
R 2
(-7225 5975);
FORCEPROP 2 LASTPIN (-7450 5850) $PN 9
J 2
(-7460 5860);
DISPLAY 0.808511 (-7460 5860);
PAINT ORANGE (-7460 5860);
FORCEPROP 2 LASTPIN (-7450 5800) $PN 10
J 2
(-7460 5810);
DISPLAY 0.808511 (-7460 5810);
PAINT ORANGE (-7460 5810);
FORCEPROP 2 LASTPIN (-7450 5750) $PN 11
J 2
(-7460 5760);
DISPLAY 0.808511 (-7460 5760);
PAINT ORANGE (-7460 5760);
FORCEPROP 1 LAST LOCATION T1D2
J 2
(-7250 6375);
DISPLAY 0.617021 (-7250 6375);
PAINT GREEN (-7250 6375);
FORCEPROP 2 LASTPIN (-7450 6200) $PN 2
J 2
(-7460 6210);
DISPLAY 0.808511 (-7460 6210);
PAINT ORANGE (-7460 6210);
FORCEPROP 2 LASTPIN (-7450 6250) $PN 1
J 2
(-7460 6260);
DISPLAY 0.808511 (-7460 6260);
PAINT ORANGE (-7460 6260);
FORCEPROP 2 LASTPIN (-7450 5700) $PN 12
J 2
(-7460 5710);
DISPLAY 0.808511 (-7460 5710);
PAINT ORANGE (-7460 5710);
FORCEPROP 2 LASTPIN (-7450 5950) $PN 7
J 2
(-7460 5960);
DISPLAY 0.808511 (-7460 5960);
PAINT ORANGE (-7460 5960);
FORCEPROP 2 LASTPIN (-7450 6000) $PN 6
J 2
(-7460 6010);
DISPLAY 0.808511 (-7460 6010);
PAINT ORANGE (-7460 6010);
FORCEPROP 2 LASTPIN (-7450 6050) $PN 5
J 2
(-7460 6060);
DISPLAY 0.808511 (-7460 6060);
PAINT ORANGE (-7460 6060);
FORCEPROP 2 LASTPIN (-7450 6100) $PN 4
J 2
(-7460 6110);
DISPLAY 0.808511 (-7460 6110);
PAINT ORANGE (-7460 6110);
FORCEPROP 2 LASTPIN (-7450 6150) $PN 3
J 2
(-7460 6160);
DISPLAY 0.808511 (-7460 6160);
PAINT ORANGE (-7460 6160);
FORCEPROP 2 LASTPIN (-7450 5900) $PN 8
J 2
(-7460 5910);
DISPLAY 0.808511 (-7460 5910);
PAINT ORANGE (-7460 5910);
FORCEPROP 1 LAST VALUE TEST-PAD-12P-1-GP-U
J 2
(-7150 5550);
DISPLAY 0.617021 (-7150 5550);
PAINT GREEN (-7150 5550);
FORCEPROP 1 LAST PATH I3
J 2
(-7225 6265);
DISPLAY 0.617021 (-7225 6265);
PAINT GREEN (-7225 6265);
DISPLAY INVISIBLE (-7225 6265);
FORCEPROP 1 LAST CDS_LMAN_SYM_OUTLINE -75,375,75,-375
J 2
(-7225 5975);
DISPLAY 0.468085 (-7225 5975);
PAINT GREEN (-7225 5975);
DISPLAY INVISIBLE (-7225 5975);
FORCEPROP 2 LAST CDS_LIB w_hdl
J 2
(-7225 5975);
DISPLAY INVISIBLE (-7225 5975);
FORCEPROP 1 LAST PART_NUMBER ZZ.00PAD.MJ1
J 2
(-7225 5686);
DISPLAY 0.617021 (-7225 5686);
PAINT GREEN (-7225 5686);
DISPLAY INVISIBLE (-7225 5686);
FORCEPROP 1 LAST PACK_TYPE DISCRET-GB1
J 2
(-7225 5975);
DISPLAY 0.617021 (-7225 5975);
PAINT GREEN (-7225 5975);
DISPLAY INVISIBLE (-7225 5975);
FORCEPROP 2 LAST SEC 1
J 2
(-7250 6425);
DISPLAY 0.680851 (-7250 6425);
PAINT MONO (-7250 6425);
DISPLAY INVISIBLE (-7250 6425);
FORCEPROP 2 LAST SEC_TYPE DISCRET-GB1
J 2
(-7250 6425);
DISPLAY 1.021277 (-7250 6425);
PAINT ORANGE (-7250 6425);
DISPLAY INVISIBLE (-7250 6425);
FORCEADD GND..1
(-7600 5600);
FORCEPROP 3 LASTPIN (-7600 5650) SIG_NAME GND\g
J 0
(-7590 5660);
DISPLAY 0.659574 (-7590 5660);
PAINT MONO (-7590 5660);
DISPLAY INVISIBLE (-7590 5660);
FORCEPROP 1 LAST PATH I4
J 0
(-7525 5600);
DISPLAY 0.872340 (-7525 5600);
PAINT AQUA (-7525 5600);
DISPLAY INVISIBLE (-7525 5600);
FORCEPROP 2 LAST CDS_LIB mstr_symbols
J 0
(-7600 5600);
DISPLAY INVISIBLE (-7600 5600);
FORCEPROP 1 LAST HDL_POWER GND
J 0
(-7600 5750);
PAINT GREEN (-7600 5750);
DISPLAY INVISIBLE (-7600 5750);
FORCEPROP 1 LAST BODY_TYPE PLUMBING
J 0
(-7645 5557);
DISPLAY 0.340426 (-7645 5557);
PAINT GREEN (-7645 5557);
DISPLAY INVISIBLE (-7645 5557);
FORCEPROP 1 LAST SIZE 1B
J 0
(-7525 5550);
DISPLAY 2.382979 (-7525 5550);
PAINT GREEN (-7525 5550);
DISPLAY INVISIBLE (-7525 5550);
FORCEPROP 1 LAST VOLTAGE 0.0V
J 0
(-7645 5557);
DISPLAY 0.340426 (-7645 5557);
PAINT SKYBLUE (-7645 5557);
DISPLAY INVISIBLE (-7645 5557);
FORCEADD TEST-PAD-12P-1-GP-U..1
(-8825 5025);
FORCEPROP 2 LASTPIN (-8600 5200) $PN 3
J 0
(-8590 5210);
DISPLAY 0.808511 (-8590 5210);
PAINT ORANGE (-8590 5210);
FORCEPROP 2 LASTPIN (-8600 5150) $PN 4
J 0
(-8590 5160);
DISPLAY 0.808511 (-8590 5160);
PAINT ORANGE (-8590 5160);
FORCEPROP 2 LASTPIN (-8600 5100) $PN 5
J 0
(-8590 5110);
DISPLAY 0.808511 (-8590 5110);
PAINT ORANGE (-8590 5110);
FORCEPROP 2 LASTPIN (-8600 5050) $PN 6
J 0
(-8590 5060);
DISPLAY 0.808511 (-8590 5060);
PAINT ORANGE (-8590 5060);
FORCEPROP 2 LASTPIN (-8600 5000) $PN 7
J 0
(-8590 5010);
DISPLAY 0.808511 (-8590 5010);
PAINT ORANGE (-8590 5010);
FORCEPROP 2 LASTPIN (-8600 4950) $PN 8
J 0
(-8590 4960);
DISPLAY 0.808511 (-8590 4960);
PAINT ORANGE (-8590 4960);
FORCEPROP 2 LASTPIN (-8600 4900) $PN 9
J 0
(-8590 4910);
DISPLAY 0.808511 (-8590 4910);
PAINT ORANGE (-8590 4910);
FORCEPROP 2 LASTPIN (-8600 4850) $PN 10
J 0
(-8590 4860);
DISPLAY 0.808511 (-8590 4860);
PAINT ORANGE (-8590 4860);
FORCEPROP 2 LASTPIN (-8600 4800) $PN 11
J 0
(-8590 4810);
DISPLAY 0.808511 (-8590 4810);
PAINT ORANGE (-8590 4810);
FORCEPROP 2 LASTPIN (-8600 4750) $PN 12
J 0
(-8590 4760);
DISPLAY 0.808511 (-8590 4760);
PAINT ORANGE (-8590 4760);
FORCEPROP 2 LASTPIN (-8600 5300) $PN 1
J 0
(-8590 5310);
DISPLAY 0.808511 (-8590 5310);
PAINT ORANGE (-8590 5310);
FORCEPROP 2 LASTPIN (-8600 5250) $PN 2
J 0
(-8590 5260);
DISPLAY 0.808511 (-8590 5260);
PAINT ORANGE (-8590 5260);
FORCEPROP 1 LAST VALUE TEST-PAD-12P-1-GP-U
J 0
(-8900 4600);
DISPLAY 0.617021 (-8900 4600);
PAINT GREEN (-8900 4600);
FORCEPROP 1 LAST LOCATION T1D3
J 0
(-8800 5425);
DISPLAY 0.617021 (-8800 5425);
PAINT GREEN (-8800 5425);
FORCEPROP 1 LAST PATH I5
J 0
(-8825 5315);
DISPLAY 0.617021 (-8825 5315);
PAINT GREEN (-8825 5315);
DISPLAY INVISIBLE (-8825 5315);
FORCEPROP 2 LAST SEC_TYPE DISCRET-GB1
J 0
(-8800 5475);
DISPLAY 1.021277 (-8800 5475);
PAINT ORANGE (-8800 5475);
DISPLAY INVISIBLE (-8800 5475);
FORCEPROP 2 LAST SEC 1
J 0
(-8800 5475);
DISPLAY 0.680851 (-8800 5475);
PAINT MONO (-8800 5475);
DISPLAY INVISIBLE (-8800 5475);
FORCEPROP 1 LAST PACK_TYPE DISCRET-GB1
J 0
(-8825 5025);
DISPLAY 0.617021 (-8825 5025);
PAINT GREEN (-8825 5025);
DISPLAY INVISIBLE (-8825 5025);
FORCEPROP 1 LAST PART_NUMBER ZZ.00PAD.MJ1
J 0
(-8825 4736);
DISPLAY 0.617021 (-8825 4736);
PAINT GREEN (-8825 4736);
DISPLAY INVISIBLE (-8825 4736);
FORCEPROP 2 LAST CDS_LIB w_hdl
J 0
(-8825 5025);
DISPLAY INVISIBLE (-8825 5025);
FORCEPROP 1 LAST CDS_LMAN_SYM_OUTLINE -75,375,75,-375
J 0
(-8825 5025);
DISPLAY 0.468085 (-8825 5025);
PAINT GREEN (-8825 5025);
DISPLAY INVISIBLE (-8825 5025);
FORCEADD TEST-PAD-12P-1-GP-U..1
R 2
(-7225 5025);
FORCEPROP 2 LASTPIN (-7450 5200) $PN 3
J 2
(-7460 5210);
DISPLAY 0.808511 (-7460 5210);
PAINT ORANGE (-7460 5210);
FORCEPROP 2 LASTPIN (-7450 5150) $PN 4
J 2
(-7460 5160);
DISPLAY 0.808511 (-7460 5160);
PAINT ORANGE (-7460 5160);
FORCEPROP 2 LASTPIN (-7450 5100) $PN 5
J 2
(-7460 5110);
DISPLAY 0.808511 (-7460 5110);
PAINT ORANGE (-7460 5110);
FORCEPROP 2 LASTPIN (-7450 5050) $PN 6
J 2
(-7460 5060);
DISPLAY 0.808511 (-7460 5060);
PAINT ORANGE (-7460 5060);
FORCEPROP 2 LASTPIN (-7450 5000) $PN 7
J 2
(-7460 5010);
DISPLAY 0.808511 (-7460 5010);
PAINT ORANGE (-7460 5010);
FORCEPROP 2 LASTPIN (-7450 4950) $PN 8
J 2
(-7460 4960);
DISPLAY 0.808511 (-7460 4960);
PAINT ORANGE (-7460 4960);
FORCEPROP 2 LASTPIN (-7450 4900) $PN 9
J 2
(-7460 4910);
DISPLAY 0.808511 (-7460 4910);
PAINT ORANGE (-7460 4910);
FORCEPROP 2 LASTPIN (-7450 4850) $PN 10
J 2
(-7460 4860);
DISPLAY 0.808511 (-7460 4860);
PAINT ORANGE (-7460 4860);
FORCEPROP 2 LASTPIN (-7450 4800) $PN 11
J 2
(-7460 4810);
DISPLAY 0.808511 (-7460 4810);
PAINT ORANGE (-7460 4810);
FORCEPROP 2 LASTPIN (-7450 4750) $PN 12
J 2
(-7460 4760);
DISPLAY 0.808511 (-7460 4760);
PAINT ORANGE (-7460 4760);
FORCEPROP 2 LASTPIN (-7450 5300) $PN 1
J 2
(-7460 5310);
DISPLAY 0.808511 (-7460 5310);
PAINT ORANGE (-7460 5310);
FORCEPROP 2 LASTPIN (-7450 5250) $PN 2
J 2
(-7460 5260);
DISPLAY 0.808511 (-7460 5260);
PAINT ORANGE (-7460 5260);
FORCEPROP 1 LAST VALUE TEST-PAD-12P-1-GP-U
J 2
(-7150 4600);
DISPLAY 0.617021 (-7150 4600);
PAINT GREEN (-7150 4600);
FORCEPROP 1 LAST LOCATION T1D4
J 2
(-7250 5425);
DISPLAY 0.617021 (-7250 5425);
PAINT GREEN (-7250 5425);
FORCEPROP 1 LAST PATH I6
J 2
(-7225 5315);
DISPLAY 0.617021 (-7225 5315);
PAINT GREEN (-7225 5315);
DISPLAY INVISIBLE (-7225 5315);
FORCEPROP 2 LAST SEC_TYPE DISCRET-GB1
J 2
(-7250 5475);
DISPLAY 1.021277 (-7250 5475);
PAINT ORANGE (-7250 5475);
DISPLAY INVISIBLE (-7250 5475);
FORCEPROP 2 LAST SEC 1
J 2
(-7250 5475);
DISPLAY 0.680851 (-7250 5475);
PAINT MONO (-7250 5475);
DISPLAY INVISIBLE (-7250 5475);
FORCEPROP 1 LAST PACK_TYPE DISCRET-GB1
J 2
(-7225 5025);
DISPLAY 0.617021 (-7225 5025);
PAINT GREEN (-7225 5025);
DISPLAY INVISIBLE (-7225 5025);
FORCEPROP 1 LAST PART_NUMBER ZZ.00PAD.MJ1
J 2
(-7225 4736);
DISPLAY 0.617021 (-7225 4736);
PAINT GREEN (-7225 4736);
DISPLAY INVISIBLE (-7225 4736);
FORCEPROP 2 LAST CDS_LIB w_hdl
J 2
(-7225 5025);
DISPLAY INVISIBLE (-7225 5025);
FORCEPROP 1 LAST CDS_LMAN_SYM_OUTLINE -75,375,75,-375
J 2
(-7225 5025);
DISPLAY 0.468085 (-7225 5025);
PAINT GREEN (-7225 5025);
DISPLAY INVISIBLE (-7225 5025);
FORCEADD GND..1
(-7600 4650);
FORCEPROP 3 LASTPIN (-7600 4700) SIG_NAME GND\g
J 0
(-7590 4710);
DISPLAY 0.659574 (-7590 4710);
PAINT MONO (-7590 4710);
DISPLAY INVISIBLE (-7590 4710);
FORCEPROP 1 LAST PATH I7
J 0
(-7525 4650);
DISPLAY 0.872340 (-7525 4650);
PAINT AQUA (-7525 4650);
DISPLAY INVISIBLE (-7525 4650);
FORCEPROP 1 LAST VOLTAGE 0.0V
J 0
(-7645 4607);
DISPLAY 0.340426 (-7645 4607);
PAINT SKYBLUE (-7645 4607);
DISPLAY INVISIBLE (-7645 4607);
FORCEPROP 1 LAST SIZE 1B
J 0
(-7525 4600);
DISPLAY 2.382979 (-7525 4600);
PAINT GREEN (-7525 4600);
DISPLAY INVISIBLE (-7525 4600);
FORCEPROP 1 LAST BODY_TYPE PLUMBING
J 0
(-7645 4607);
DISPLAY 0.340426 (-7645 4607);
PAINT GREEN (-7645 4607);
DISPLAY INVISIBLE (-7645 4607);
FORCEPROP 1 LAST HDL_POWER GND
J 0
(-7600 4800);
PAINT GREEN (-7600 4800);
DISPLAY INVISIBLE (-7600 4800);
FORCEPROP 2 LAST CDS_LIB mstr_symbols
J 0
(-7600 4650);
DISPLAY INVISIBLE (-7600 4650);
FORCEADD GND..1
(-8450 4650);
FORCEPROP 3 LASTPIN (-8450 4700) SIG_NAME GND\g
J 0
(-8440 4710);
DISPLAY 0.659574 (-8440 4710);
PAINT MONO (-8440 4710);
DISPLAY INVISIBLE (-8440 4710);
FORCEPROP 1 LAST PATH I8
J 0
(-8375 4650);
DISPLAY 0.872340 (-8375 4650);
PAINT AQUA (-8375 4650);
DISPLAY INVISIBLE (-8375 4650);
FORCEPROP 2 LAST CDS_LIB mstr_symbols
J 0
(-8450 4650);
DISPLAY INVISIBLE (-8450 4650);
FORCEPROP 1 LAST HDL_POWER GND
J 0
(-8450 4800);
PAINT GREEN (-8450 4800);
DISPLAY INVISIBLE (-8450 4800);
FORCEPROP 1 LAST BODY_TYPE PLUMBING
J 0
(-8495 4607);
DISPLAY 0.340426 (-8495 4607);
PAINT GREEN (-8495 4607);
DISPLAY INVISIBLE (-8495 4607);
FORCEPROP 1 LAST SIZE 1B
J 0
(-8375 4600);
DISPLAY 2.382979 (-8375 4600);
PAINT GREEN (-8375 4600);
DISPLAY INVISIBLE (-8375 4600);
FORCEPROP 1 LAST VOLTAGE 0.0V
J 0
(-8495 4607);
DISPLAY 0.340426 (-8495 4607);
PAINT SKYBLUE (-8495 4607);
DISPLAY INVISIBLE (-8495 4607);
FORCEADD TEST-PAD-12P-1-GP-U..1
R 2
(-7225 4075);
FORCEPROP 2 LASTPIN (-7450 4250) $PN 3
J 2
(-7460 4260);
DISPLAY 0.808511 (-7460 4260);
PAINT ORANGE (-7460 4260);
FORCEPROP 2 LASTPIN (-7450 4200) $PN 4
J 2
(-7460 4210);
DISPLAY 0.808511 (-7460 4210);
PAINT ORANGE (-7460 4210);
FORCEPROP 2 LASTPIN (-7450 4150) $PN 5
J 2
(-7460 4160);
DISPLAY 0.808511 (-7460 4160);
PAINT ORANGE (-7460 4160);
FORCEPROP 2 LASTPIN (-7450 4100) $PN 6
J 2
(-7460 4110);
DISPLAY 0.808511 (-7460 4110);
PAINT ORANGE (-7460 4110);
FORCEPROP 2 LASTPIN (-7450 4050) $PN 7
J 2
(-7460 4060);
DISPLAY 0.808511 (-7460 4060);
PAINT ORANGE (-7460 4060);
FORCEPROP 2 LASTPIN (-7450 4000) $PN 8
J 2
(-7460 4010);
DISPLAY 0.808511 (-7460 4010);
PAINT ORANGE (-7460 4010);
FORCEPROP 2 LASTPIN (-7450 3950) $PN 9
J 2
(-7460 3960);
DISPLAY 0.808511 (-7460 3960);
PAINT ORANGE (-7460 3960);
FORCEPROP 2 LASTPIN (-7450 3900) $PN 10
J 2
(-7460 3910);
DISPLAY 0.808511 (-7460 3910);
PAINT ORANGE (-7460 3910);
FORCEPROP 2 LASTPIN (-7450 3850) $PN 11
J 2
(-7460 3860);
DISPLAY 0.808511 (-7460 3860);
PAINT ORANGE (-7460 3860);
FORCEPROP 2 LASTPIN (-7450 3800) $PN 12
J 2
(-7460 3810);
DISPLAY 0.808511 (-7460 3810);
PAINT ORANGE (-7460 3810);
FORCEPROP 2 LASTPIN (-7450 4350) $PN 1
J 2
(-7460 4360);
DISPLAY 0.808511 (-7460 4360);
PAINT ORANGE (-7460 4360);
FORCEPROP 2 LASTPIN (-7450 4300) $PN 2
J 2
(-7460 4310);
DISPLAY 0.808511 (-7460 4310);
PAINT ORANGE (-7460 4310);
FORCEPROP 1 LAST LOCATION T1D6
J 2
(-7250 4475);
DISPLAY 0.617021 (-7250 4475);
PAINT GREEN (-7250 4475);
FORCEPROP 1 LAST VALUE TEST-PAD-12P-1-GP-U
J 2
(-7150 3650);
DISPLAY 0.617021 (-7150 3650);
PAINT GREEN (-7150 3650);
FORCEPROP 1 LAST PATH I9
J 2
(-7225 4365);
DISPLAY 0.617021 (-7225 4365);
PAINT GREEN (-7225 4365);
DISPLAY INVISIBLE (-7225 4365);
FORCEPROP 2 LAST SEC_TYPE DISCRET-GB1
J 2
(-7250 4525);
DISPLAY 1.021277 (-7250 4525);
PAINT ORANGE (-7250 4525);
DISPLAY INVISIBLE (-7250 4525);
FORCEPROP 2 LAST SEC 1
J 2
(-7250 4525);
DISPLAY 0.680851 (-7250 4525);
PAINT MONO (-7250 4525);
DISPLAY INVISIBLE (-7250 4525);
FORCEPROP 1 LAST PACK_TYPE DISCRET-GB1
J 2
(-7225 4075);
DISPLAY 0.617021 (-7225 4075);
PAINT GREEN (-7225 4075);
DISPLAY INVISIBLE (-7225 4075);
FORCEPROP 1 LAST PART_NUMBER ZZ.00PAD.MJ1
J 2
(-7225 3786);
DISPLAY 0.617021 (-7225 3786);
PAINT GREEN (-7225 3786);
DISPLAY INVISIBLE (-7225 3786);
FORCEPROP 2 LAST CDS_LIB w_hdl
J 2
(-7225 4075);
DISPLAY INVISIBLE (-7225 4075);
FORCEPROP 1 LAST CDS_LMAN_SYM_OUTLINE -75,375,75,-375
J 2
(-7225 4075);
DISPLAY 0.468085 (-7225 4075);
PAINT GREEN (-7225 4075);
DISPLAY INVISIBLE (-7225 4075);
FORCEADD INTEL_CORP_BPAGE..1
(-1300 1525);
FORCEPROP 1 LAST CDS_CON_LAST_MODIFIED Fri Jun 16 17:49:34 2017
J 0
(-2725 1850);
PAINT ORANGE (-2725 1850);
DISPLAY INVISIBLE (-2725 1850);
FORCEPROP 1 LAST CUSTOM_TXT_CDS <CON_LAST_MODIFIED>
J 0
(-5300 1625);
PAINT ORANGE (-5300 1625);
FORCEPROP 2 LAST CUSTOM_TXT_CDS <XR_PAGE_TITLE>
J 0
(-9190 6775);
DISPLAY 0.638298 (-9190 6775);
PAINT PINK (-9190 6775);
DISPLAY INVISIBLE (-9190 6775);
FORCEPROP 2 LAST CUSTOM_TXT_CDS <CURRENT_DESIGN_SHEET> OF <TOTAL_DESIGN_SHEETS>
J 0
(-1800 1550);
PAINT ORANGE (-1800 1550);
FORCEPROP 2 LAST CUSTOM_TXT_CDS Thu Nov 17 16:16:25 2016
J 0
(-5300 1625);
PAINT ORANGE (-5300 1625);
FORCEPROP 1 LAST SCH_TITLE COUPON - 2 OF 3
J 0
(-9250 1575);
DISPLAY 2.468085 (-9250 1575);
PAINT ORANGE (-9250 1575);
FORCEPROP 1 LAST COMMENT_BODY TRUE
J 0
(-1288 1537);
DISPLAY 0.468085 (-1288 1537);
PAINT GREEN (-1288 1537);
DISPLAY INVISIBLE (-1288 1537);
FORCEPROP 2 LAST CDS_LIB mstr_symbols
J 0
(-1300 1525);
PAINT MONO (-1300 1525);
DISPLAY INVISIBLE (-1300 1525);
FORCEPROP 2 LAST PAGE_BORDER TRUE
J 0
(-9190 6775);
DISPLAY 0.638298 (-9190 6775);
PAINT PINK (-9190 6775);
DISPLAY INVISIBLE (-9190 6775);
FORCEPROP 2 LAST CDS_XR_PAGE_TITLE CR-257 : @BASEBOARD_FAB2_LIB.BASEBOARD_FAB2(SCH_1):PAGE257
J 0
(-9190 6775);
DISPLAY 0.638298 (-9190 6775);
PAINT PINK (-9190 6775);
DISPLAY INVISIBLE (-9190 6775);
WIRE 16 -1 (-7600 3750)(-7600 3800);
WIRE 16 -1 (-7600 3800)(-7600 3850);
WIRE 16 -1 (-7450 3800)(-7600 3800);
WIRE 16 -1 (-7600 3850)(-7600 3900);
WIRE 16 -1 (-7450 3850)(-7600 3850);
WIRE 16 -1 (-7600 3900)(-7600 3950);
WIRE 16 -1 (-7450 3900)(-7600 3900);
WIRE 16 -1 (-7600 3950)(-7600 4000);
WIRE 16 -1 (-7450 3950)(-7600 3950);
WIRE 16 -1 (-7600 4000)(-7600 4050);
WIRE 16 -1 (-7450 4000)(-7600 4000);
WIRE 16 -1 (-7600 4050)(-7600 4100);
WIRE 16 -1 (-7450 4050)(-7600 4050);
WIRE 16 -1 (-7600 4100)(-7600 4150);
WIRE 16 -1 (-7450 4100)(-7600 4100);
WIRE 16 -1 (-7600 4150)(-7600 4200);
WIRE 16 -1 (-7450 4150)(-7600 4150);
WIRE 16 -1 (-7600 4200)(-7600 4250);
WIRE 16 -1 (-7450 4200)(-7600 4200);
WIRE 16 -1 (-7450 4250)(-7600 4250);
WIRE 16 -1 (-8450 3750)(-8450 3800);
WIRE 16 -1 (-8450 3850)(-8450 3800);
WIRE 16 -1 (-8600 3800)(-8450 3800);
WIRE 16 -1 (-8450 3900)(-8450 3850);
WIRE 16 -1 (-8600 3850)(-8450 3850);
WIRE 16 -1 (-8450 3950)(-8450 3900);
WIRE 16 -1 (-8600 3900)(-8450 3900);
WIRE 16 -1 (-8450 4000)(-8450 3950);
WIRE 16 -1 (-8600 3950)(-8450 3950);
WIRE 16 -1 (-8450 4050)(-8450 4000);
WIRE 16 -1 (-8600 4000)(-8450 4000);
WIRE 16 -1 (-8450 4100)(-8450 4050);
WIRE 16 -1 (-8600 4050)(-8450 4050);
WIRE 16 -1 (-8450 4150)(-8450 4100);
WIRE 16 -1 (-8600 4100)(-8450 4100);
WIRE 16 -1 (-8450 4200)(-8450 4150);
WIRE 16 -1 (-8600 4150)(-8450 4150);
WIRE 16 -1 (-8450 4250)(-8450 4200);
WIRE 16 -1 (-8600 4200)(-8450 4200);
WIRE 16 -1 (-8600 4250)(-8450 4250);
WIRE 16 -1 (-5150 5675)(-5150 5725);
WIRE 16 -1 (-5150 5725)(-5150 5775);
WIRE 16 -1 (-5000 5725)(-5150 5725);
WIRE 16 -1 (-5150 5775)(-5150 5825);
WIRE 16 -1 (-5000 5775)(-5150 5775);
WIRE 16 -1 (-5150 5825)(-5150 5875);
WIRE 16 -1 (-5000 5825)(-5150 5825);
WIRE 16 -1 (-5150 5875)(-5150 5925);
WIRE 16 -1 (-5000 5875)(-5150 5875);
WIRE 16 -1 (-5150 5925)(-5150 5975);
WIRE 16 -1 (-5000 5925)(-5150 5925);
WIRE 16 -1 (-5150 5975)(-5150 6025);
WIRE 16 -1 (-5000 5975)(-5150 5975);
WIRE 16 -1 (-5150 6025)(-5150 6075);
WIRE 16 -1 (-5000 6025)(-5150 6025);
WIRE 16 -1 (-5150 6075)(-5150 6125);
WIRE 16 -1 (-5000 6075)(-5150 6075);
WIRE 16 -1 (-5150 6125)(-5150 6175);
WIRE 16 -1 (-5000 6125)(-5150 6125);
WIRE 16 -1 (-5000 6175)(-5150 6175);
WIRE 16 -1 (-6000 5675)(-6000 5725);
WIRE 16 -1 (-6000 5775)(-6000 5725);
WIRE 16 -1 (-6150 5725)(-6000 5725);
WIRE 16 -1 (-6000 5825)(-6000 5775);
WIRE 16 -1 (-6150 5775)(-6000 5775);
WIRE 16 -1 (-6000 5875)(-6000 5825);
WIRE 16 -1 (-6150 5825)(-6000 5825);
WIRE 16 -1 (-6000 5925)(-6000 5875);
WIRE 16 -1 (-6150 5875)(-6000 5875);
WIRE 16 -1 (-6000 5975)(-6000 5925);
WIRE 16 -1 (-6150 5925)(-6000 5925);
WIRE 16 -1 (-6000 6025)(-6000 5975);
WIRE 16 -1 (-6150 5975)(-6000 5975);
WIRE 16 -1 (-6000 6075)(-6000 6025);
WIRE 16 -1 (-6150 6025)(-6000 6025);
WIRE 16 -1 (-6000 6125)(-6000 6075);
WIRE 16 -1 (-6150 6075)(-6000 6075);
WIRE 16 -1 (-6000 6175)(-6000 6125);
WIRE 16 -1 (-6150 6125)(-6000 6125);
WIRE 16 -1 (-6150 6175)(-6000 6175);
WIRE 16 -1 (-5150 4725)(-5150 4775);
WIRE 16 -1 (-5150 4775)(-5150 4825);
WIRE 16 -1 (-5000 4775)(-5150 4775);
WIRE 16 -1 (-5150 4825)(-5150 4875);
WIRE 16 -1 (-5000 4825)(-5150 4825);
WIRE 16 -1 (-5150 4875)(-5150 4925);
WIRE 16 -1 (-5000 4875)(-5150 4875);
WIRE 16 -1 (-5150 4925)(-5150 4975);
WIRE 16 -1 (-5000 4925)(-5150 4925);
WIRE 16 -1 (-5150 4975)(-5150 5025);
WIRE 16 -1 (-5000 4975)(-5150 4975);
WIRE 16 -1 (-5150 5025)(-5150 5075);
WIRE 16 -1 (-5000 5025)(-5150 5025);
WIRE 16 -1 (-5150 5075)(-5150 5125);
WIRE 16 -1 (-5000 5075)(-5150 5075);
WIRE 16 -1 (-5150 5125)(-5150 5175);
WIRE 16 -1 (-5000 5125)(-5150 5125);
WIRE 16 -1 (-5150 5175)(-5150 5225);
WIRE 16 -1 (-5000 5175)(-5150 5175);
WIRE 16 -1 (-5000 5225)(-5150 5225);
WIRE 16 -1 (-8450 5650)(-8450 5700);
WIRE 16 -1 (-8450 5750)(-8450 5700);
WIRE 16 -1 (-8600 5700)(-8450 5700);
WIRE 16 -1 (-8450 5800)(-8450 5750);
WIRE 16 -1 (-8600 5750)(-8450 5750);
WIRE 16 -1 (-8450 5850)(-8450 5800);
WIRE 16 -1 (-8600 5800)(-8450 5800);
WIRE 16 -1 (-8450 5900)(-8450 5850);
WIRE 16 -1 (-8600 5850)(-8450 5850);
WIRE 16 -1 (-8450 5950)(-8450 5900);
WIRE 16 -1 (-8600 5900)(-8450 5900);
WIRE 16 -1 (-8450 6000)(-8450 5950);
WIRE 16 -1 (-8600 5950)(-8450 5950);
WIRE 16 -1 (-8450 6050)(-8450 6000);
WIRE 16 -1 (-8600 6000)(-8450 6000);
WIRE 16 -1 (-8450 6100)(-8450 6050);
WIRE 16 -1 (-8600 6050)(-8450 6050);
WIRE 16 -1 (-8450 6150)(-8450 6100);
WIRE 16 -1 (-8600 6100)(-8450 6100);
WIRE 16 -1 (-8600 6150)(-8450 6150);
WIRE 16 -1 (-6000 4725)(-6000 4775);
WIRE 16 -1 (-6000 4825)(-6000 4775);
WIRE 16 -1 (-6150 4775)(-6000 4775);
WIRE 16 -1 (-6000 4875)(-6000 4825);
WIRE 16 -1 (-6150 4825)(-6000 4825);
WIRE 16 -1 (-6000 4925)(-6000 4875);
WIRE 16 -1 (-6150 4875)(-6000 4875);
WIRE 16 -1 (-6000 4975)(-6000 4925);
WIRE 16 -1 (-6150 4925)(-6000 4925);
WIRE 16 -1 (-6000 5025)(-6000 4975);
WIRE 16 -1 (-6150 4975)(-6000 4975);
WIRE 16 -1 (-6000 5075)(-6000 5025);
WIRE 16 -1 (-6150 5025)(-6000 5025);
WIRE 16 -1 (-6000 5125)(-6000 5075);
WIRE 16 -1 (-6150 5075)(-6000 5075);
WIRE 16 -1 (-6000 5175)(-6000 5125);
WIRE 16 -1 (-6150 5125)(-6000 5125);
WIRE 16 -1 (-6000 5225)(-6000 5175);
WIRE 16 -1 (-6150 5175)(-6000 5175);
WIRE 16 -1 (-6150 5225)(-6000 5225);
WIRE 16 -1 (-5150 3775)(-5150 3825);
WIRE 16 -1 (-5150 3825)(-5150 3875);
WIRE 16 -1 (-5000 3825)(-5150 3825);
WIRE 16 -1 (-5150 3875)(-5150 3925);
WIRE 16 -1 (-5000 3875)(-5150 3875);
WIRE 16 -1 (-5150 3925)(-5150 3975);
WIRE 16 -1 (-5000 3925)(-5150 3925);
WIRE 16 -1 (-5150 3975)(-5150 4025);
WIRE 16 -1 (-5000 3975)(-5150 3975);
WIRE 16 -1 (-5150 4025)(-5150 4075);
WIRE 16 -1 (-5000 4025)(-5150 4025);
WIRE 16 -1 (-5150 4075)(-5150 4125);
WIRE 16 -1 (-5000 4075)(-5150 4075);
WIRE 16 -1 (-5150 4125)(-5150 4175);
WIRE 16 -1 (-5000 4125)(-5150 4125);
WIRE 16 -1 (-5150 4175)(-5150 4225);
WIRE 16 -1 (-5000 4175)(-5150 4175);
WIRE 16 -1 (-5150 4225)(-5150 4275);
WIRE 16 -1 (-5000 4225)(-5150 4225);
WIRE 16 -1 (-5000 4275)(-5150 4275);
WIRE 16 -1 (-6000 3775)(-6000 3825);
WIRE 16 -1 (-6000 3875)(-6000 3825);
WIRE 16 -1 (-6150 3825)(-6000 3825);
WIRE 16 -1 (-6000 3925)(-6000 3875);
WIRE 16 -1 (-6150 3875)(-6000 3875);
WIRE 16 -1 (-6000 3975)(-6000 3925);
WIRE 16 -1 (-6150 3925)(-6000 3925);
WIRE 16 -1 (-6000 4025)(-6000 3975);
WIRE 16 -1 (-6150 3975)(-6000 3975);
WIRE 16 -1 (-6000 4075)(-6000 4025);
WIRE 16 -1 (-6150 4025)(-6000 4025);
WIRE 16 -1 (-6000 4125)(-6000 4075);
WIRE 16 -1 (-6150 4075)(-6000 4075);
WIRE 16 -1 (-6000 4175)(-6000 4125);
WIRE 16 -1 (-6150 4125)(-6000 4125);
WIRE 16 -1 (-6000 4225)(-6000 4175);
WIRE 16 -1 (-6150 4175)(-6000 4175);
WIRE 16 -1 (-6000 4275)(-6000 4225);
WIRE 16 -1 (-6150 4225)(-6000 4225);
WIRE 16 -1 (-6150 4275)(-6000 4275);
WIRE 16 -1 (-7600 5650)(-7600 5700);
WIRE 16 -1 (-7600 5700)(-7600 5750);
WIRE 16 -1 (-7450 5700)(-7600 5700);
WIRE 16 -1 (-7600 5750)(-7600 5800);
WIRE 16 -1 (-7450 5750)(-7600 5750);
WIRE 16 -1 (-7600 5800)(-7600 5850);
WIRE 16 -1 (-7450 5800)(-7600 5800);
WIRE 16 -1 (-7600 5850)(-7600 5900);
WIRE 16 -1 (-7450 5850)(-7600 5850);
WIRE 16 -1 (-7600 5900)(-7600 5950);
WIRE 16 -1 (-7450 5900)(-7600 5900);
WIRE 16 -1 (-7600 5950)(-7600 6000);
WIRE 16 -1 (-7450 5950)(-7600 5950);
WIRE 16 -1 (-7600 6000)(-7600 6050);
WIRE 16 -1 (-7450 6000)(-7600 6000);
WIRE 16 -1 (-7600 6050)(-7600 6100);
WIRE 16 -1 (-7450 6050)(-7600 6050);
WIRE 16 -1 (-7600 6100)(-7600 6150);
WIRE 16 -1 (-7450 6100)(-7600 6100);
WIRE 16 -1 (-7450 6150)(-7600 6150);
WIRE 16 -1 (-7600 4700)(-7600 4750);
WIRE 16 -1 (-7600 4750)(-7600 4800);
WIRE 16 -1 (-7450 4750)(-7600 4750);
WIRE 16 -1 (-7600 4800)(-7600 4850);
WIRE 16 -1 (-7450 4800)(-7600 4800);
WIRE 16 -1 (-7600 4850)(-7600 4900);
WIRE 16 -1 (-7450 4850)(-7600 4850);
WIRE 16 -1 (-7600 4900)(-7600 4950);
WIRE 16 -1 (-7450 4900)(-7600 4900);
WIRE 16 -1 (-7600 4950)(-7600 5000);
WIRE 16 -1 (-7450 4950)(-7600 4950);
WIRE 16 -1 (-7600 5000)(-7600 5050);
WIRE 16 -1 (-7450 5000)(-7600 5000);
WIRE 16 -1 (-7600 5050)(-7600 5100);
WIRE 16 -1 (-7450 5050)(-7600 5050);
WIRE 16 -1 (-7600 5100)(-7600 5150);
WIRE 16 -1 (-7450 5100)(-7600 5100);
WIRE 16 -1 (-7600 5150)(-7600 5200);
WIRE 16 -1 (-7450 5150)(-7600 5150);
WIRE 16 -1 (-7450 5200)(-7600 5200);
WIRE 16 -1 (-8450 4700)(-8450 4750);
WIRE 16 -1 (-8450 4800)(-8450 4750);
WIRE 16 -1 (-8600 4750)(-8450 4750);
WIRE 16 -1 (-8450 4850)(-8450 4800);
WIRE 16 -1 (-8600 4800)(-8450 4800);
WIRE 16 -1 (-8450 4900)(-8450 4850);
WIRE 16 -1 (-8600 4850)(-8450 4850);
WIRE 16 -1 (-8450 4950)(-8450 4900);
WIRE 16 -1 (-8600 4900)(-8450 4900);
WIRE 16 -1 (-8450 5000)(-8450 4950);
WIRE 16 -1 (-8600 4950)(-8450 4950);
WIRE 16 -1 (-8450 5050)(-8450 5000);
WIRE 16 -1 (-8600 5000)(-8450 5000);
WIRE 16 -1 (-8450 5100)(-8450 5050);
WIRE 16 -1 (-8600 5050)(-8450 5050);
WIRE 16 -1 (-8450 5150)(-8450 5100);
WIRE 16 -1 (-8600 5100)(-8450 5100);
WIRE 16 -1 (-8450 5200)(-8450 5150);
WIRE 16 -1 (-8600 5150)(-8450 5150);
WIRE 16 -1 (-8600 5200)(-8450 5200);
WIRE 16 -1 (-6150 4375)(-5600 4375);
FORCEPROP 2 LAST SIG_NAME L14_85OHM_5INCH_DP
J 0
(-5985 4385);
DISPLAY 0.510638 (-5985 4385);
PAINT ORANGE (-5985 4385);
FORCEPROP 2 LASTPROP $XR0 257 
J 0
(-5570 4375);
DISPLAY 0.638298 (-5570 4375);
PAINT MONO (-5570 4375);
DISPLAY INVISIBLE (-5570 4375);
WIRE 16 -1 (-6150 4325)(-5600 4325);
FORCEPROP 2 LAST SIG_NAME L14_85OHM_5INCH_DN
J 0
(-5985 4335);
DISPLAY 0.510638 (-5985 4335);
PAINT ORANGE (-5985 4335);
FORCEPROP 2 LASTPROP $XR0 257 
J 0
(-5570 4325);
DISPLAY 0.638298 (-5570 4325);
PAINT MONO (-5570 4325);
DISPLAY INVISIBLE (-5570 4325);
WIRE 16 -1 (-5550 5325)(-5000 5325);
FORCEPROP 2 LAST SIG_NAME L12_85OHM_5INCH_DN
J 0
(-5385 5335);
DISPLAY 0.510638 (-5385 5335);
PAINT ORANGE (-5385 5335);
FORCEPROP 2 LASTPROP $XR0 257 
J 0
(-5820 5325);
DISPLAY 0.638298 (-5820 5325);
PAINT MONO (-5820 5325);
DISPLAY INVISIBLE (-5820 5325);
WIRE 16 -1 (-5550 5275)(-5000 5275);
FORCEPROP 2 LAST SIG_NAME L12_85OHM_5INCH_DP
J 0
(-5385 5285);
DISPLAY 0.510638 (-5385 5285);
PAINT ORANGE (-5385 5285);
FORCEPROP 2 LASTPROP $XR0 257 
J 0
(-5820 5275);
DISPLAY 0.638298 (-5820 5275);
PAINT MONO (-5820 5275);
DISPLAY INVISIBLE (-5820 5275);
WIRE 16 -1 (-6150 5275)(-5600 5275);
FORCEPROP 2 LAST SIG_NAME L12_85OHM_5INCH_DN
J 0
(-5985 5285);
DISPLAY 0.510638 (-5985 5285);
PAINT ORANGE (-5985 5285);
FORCEPROP 2 LASTPROP $XR0 257 
J 0
(-5570 5275);
DISPLAY 0.638298 (-5570 5275);
PAINT MONO (-5570 5275);
DISPLAY INVISIBLE (-5570 5275);
WIRE 16 -1 (-6150 5325)(-5600 5325);
FORCEPROP 2 LAST SIG_NAME L12_85OHM_5INCH_DP
J 0
(-5985 5335);
DISPLAY 0.510638 (-5985 5335);
PAINT ORANGE (-5985 5335);
FORCEPROP 2 LASTPROP $XR0 257 
J 0
(-5570 5325);
DISPLAY 0.638298 (-5570 5325);
PAINT MONO (-5570 5325);
DISPLAY INVISIBLE (-5570 5325);
WIRE 16 -1 (-5550 4325)(-5000 4325);
FORCEPROP 2 LAST SIG_NAME L14_85OHM_5INCH_DP
J 0
(-5385 4335);
DISPLAY 0.510638 (-5385 4335);
PAINT ORANGE (-5385 4335);
FORCEPROP 2 LASTPROP $XR0 257 
J 0
(-5820 4325);
DISPLAY 0.638298 (-5820 4325);
PAINT MONO (-5820 4325);
DISPLAY INVISIBLE (-5820 4325);
WIRE 16 -1 (-5550 4375)(-5000 4375);
FORCEPROP 2 LAST SIG_NAME L14_85OHM_5INCH_DN
J 0
(-5385 4385);
DISPLAY 0.510638 (-5385 4385);
PAINT ORANGE (-5385 4385);
FORCEPROP 2 LASTPROP $XR0 257 
J 0
(-5820 4375);
DISPLAY 0.638298 (-5820 4375);
PAINT MONO (-5820 4375);
DISPLAY INVISIBLE (-5820 4375);
WIRE 16 -1 (-6150 6225)(-5600 6225);
FORCEPROP 2 LAST SIG_NAME L10_85OHM_5INCH_DN
J 0
(-5985 6235);
DISPLAY 0.510638 (-5985 6235);
PAINT ORANGE (-5985 6235);
FORCEPROP 2 LASTPROP $XR0 257 
J 0
(-5570 6225);
DISPLAY 0.638298 (-5570 6225);
PAINT MONO (-5570 6225);
DISPLAY INVISIBLE (-5570 6225);
WIRE 16 -1 (-6150 6275)(-5600 6275);
FORCEPROP 2 LAST SIG_NAME L10_85OHM_5INCH_DP
J 0
(-5985 6285);
DISPLAY 0.510638 (-5985 6285);
PAINT ORANGE (-5985 6285);
FORCEPROP 2 LASTPROP $XR0 257 
J 0
(-5570 6275);
DISPLAY 0.638298 (-5570 6275);
PAINT MONO (-5570 6275);
DISPLAY INVISIBLE (-5570 6275);
WIRE 16 -1 (-5550 6275)(-5000 6275);
FORCEPROP 2 LAST SIG_NAME L10_85OHM_5INCH_DN
J 0
(-5385 6285);
DISPLAY 0.510638 (-5385 6285);
PAINT ORANGE (-5385 6285);
FORCEPROP 2 LASTPROP $XR0 257 
J 0
(-5820 6275);
DISPLAY 0.638298 (-5820 6275);
PAINT MONO (-5820 6275);
DISPLAY INVISIBLE (-5820 6275);
WIRE 16 -1 (-5550 6225)(-5000 6225);
FORCEPROP 2 LAST SIG_NAME L10_85OHM_5INCH_DP
J 0
(-5385 6235);
DISPLAY 0.510638 (-5385 6235);
PAINT ORANGE (-5385 6235);
FORCEPROP 2 LASTPROP $XR0 257 
J 0
(-5820 6225);
DISPLAY 0.638298 (-5820 6225);
PAINT MONO (-5820 6225);
DISPLAY INVISIBLE (-5820 6225);
WIRE 16 -1 (-8000 4300)(-7450 4300);
FORCEPROP 2 LAST SIG_NAME L5_85OHM_5INCH_DP
J 0
(-7835 4310);
DISPLAY 0.510638 (-7835 4310);
PAINT ORANGE (-7835 4310);
FORCEPROP 2 LASTPROP $XR0 257 
J 0
(-8270 4300);
DISPLAY 0.638298 (-8270 4300);
PAINT MONO (-8270 4300);
DISPLAY INVISIBLE (-8270 4300);
WIRE 16 -1 (-8000 4350)(-7450 4350);
FORCEPROP 2 LAST SIG_NAME L5_85OHM_5INCH_DN
J 0
(-7835 4360);
DISPLAY 0.510638 (-7835 4360);
PAINT ORANGE (-7835 4360);
FORCEPROP 2 LASTPROP $XR0 257 
J 0
(-8270 4350);
DISPLAY 0.638298 (-8270 4350);
PAINT MONO (-8270 4350);
DISPLAY INVISIBLE (-8270 4350);
WIRE 16 -1 (-8000 5250)(-7450 5250);
FORCEPROP 2 LAST SIG_NAME L3_85OHM_5INCH_DP
J 0
(-7835 5260);
DISPLAY 0.510638 (-7835 5260);
PAINT ORANGE (-7835 5260);
FORCEPROP 2 LASTPROP $XR0 257 
J 0
(-8270 5250);
DISPLAY 0.638298 (-8270 5250);
PAINT MONO (-8270 5250);
DISPLAY INVISIBLE (-8270 5250);
WIRE 16 -1 (-8600 5250)(-8050 5250);
FORCEPROP 2 LAST SIG_NAME L3_85OHM_5INCH_DN
J 0
(-8435 5260);
DISPLAY 0.510638 (-8435 5260);
PAINT ORANGE (-8435 5260);
FORCEPROP 2 LASTPROP $XR0 257 
J 0
(-8020 5250);
DISPLAY 0.638298 (-8020 5250);
PAINT MONO (-8020 5250);
DISPLAY INVISIBLE (-8020 5250);
WIRE 16 -1 (-8000 5300)(-7450 5300);
FORCEPROP 2 LAST SIG_NAME L3_85OHM_5INCH_DN
J 0
(-7835 5310);
DISPLAY 0.510638 (-7835 5310);
PAINT ORANGE (-7835 5310);
FORCEPROP 2 LASTPROP $XR0 257 
J 0
(-8270 5300);
DISPLAY 0.638298 (-8270 5300);
PAINT MONO (-8270 5300);
DISPLAY INVISIBLE (-8270 5300);
WIRE 16 -1 (-8000 6200)(-7450 6200);
FORCEPROP 2 LAST SIG_NAME L1_85OHM_5INCH_DP
J 0
(-7835 6210);
DISPLAY 0.510638 (-7835 6210);
PAINT ORANGE (-7835 6210);
FORCEPROP 2 LASTPROP $XR0 257 
J 0
(-8270 6200);
DISPLAY 0.638298 (-8270 6200);
PAINT MONO (-8270 6200);
DISPLAY INVISIBLE (-8270 6200);
WIRE 16 -1 (-8000 6250)(-7450 6250);
FORCEPROP 2 LAST SIG_NAME L1_85OHM_5INCH_DN
J 0
(-7835 6260);
DISPLAY 0.510638 (-7835 6260);
PAINT ORANGE (-7835 6260);
FORCEPROP 2 LASTPROP $XR0 257 
J 0
(-8270 6250);
DISPLAY 0.638298 (-8270 6250);
PAINT MONO (-8270 6250);
DISPLAY INVISIBLE (-8270 6250);
WIRE 16 -1 (-8600 6200)(-8050 6200);
FORCEPROP 2 LAST SIG_NAME L1_85OHM_5INCH_DN
J 0
(-8435 6210);
DISPLAY 0.510638 (-8435 6210);
PAINT ORANGE (-8435 6210);
FORCEPROP 2 LASTPROP $XR0 257 
J 0
(-8020 6200);
DISPLAY 0.638298 (-8020 6200);
PAINT MONO (-8020 6200);
DISPLAY INVISIBLE (-8020 6200);
WIRE 16 -1 (-8600 6250)(-8050 6250);
FORCEPROP 2 LAST SIG_NAME L1_85OHM_5INCH_DP
J 0
(-8435 6260);
DISPLAY 0.510638 (-8435 6260);
PAINT ORANGE (-8435 6260);
FORCEPROP 2 LASTPROP $XR0 257 
J 0
(-8020 6250);
DISPLAY 0.638298 (-8020 6250);
PAINT MONO (-8020 6250);
DISPLAY INVISIBLE (-8020 6250);
WIRE 16 -1 (-8600 5300)(-8050 5300);
FORCEPROP 2 LAST SIG_NAME L3_85OHM_5INCH_DP
J 0
(-8435 5310);
DISPLAY 0.510638 (-8435 5310);
PAINT ORANGE (-8435 5310);
FORCEPROP 2 LASTPROP $XR0 257 
J 0
(-8020 5300);
DISPLAY 0.638298 (-8020 5300);
PAINT MONO (-8020 5300);
DISPLAY INVISIBLE (-8020 5300);
WIRE 16 -1 (-8600 4300)(-8050 4300);
FORCEPROP 2 LAST SIG_NAME L5_85OHM_5INCH_DN
J 0
(-8435 4310);
DISPLAY 0.510638 (-8435 4310);
PAINT ORANGE (-8435 4310);
FORCEPROP 2 LASTPROP $XR0 257 
J 0
(-8020 4300);
DISPLAY 0.638298 (-8020 4300);
PAINT MONO (-8020 4300);
DISPLAY INVISIBLE (-8020 4300);
WIRE 16 -1 (-8600 4350)(-8050 4350);
FORCEPROP 2 LAST SIG_NAME L5_85OHM_5INCH_DP
J 0
(-8435 4360);
DISPLAY 0.510638 (-8435 4360);
PAINT ORANGE (-8435 4360);
FORCEPROP 2 LASTPROP $XR0 257 
J 0
(-8020 4350);
DISPLAY 0.638298 (-8020 4350);
PAINT MONO (-8020 4350);
DISPLAY INVISIBLE (-8020 4350);
DOT 1 (-7600 6100);
DOT 1 (-7600 6050);
DOT 1 (-7600 6000);
DOT 1 (-7600 5900);
DOT 1 (-7600 5850);
DOT 1 (-7600 5800);
DOT 1 (-7600 5700);
DOT 1 (-8450 6100);
DOT 1 (-8450 6050);
DOT 1 (-8450 5950);
DOT 1 (-8450 6000);
DOT 1 (-8450 5900);
DOT 1 (-8450 5850);
DOT 1 (-8450 5800);
DOT 1 (-8450 5750);
DOT 1 (-8450 5700);
DOT 1 (-8450 4750);
DOT 1 (-8450 4800);
DOT 1 (-8450 4850);
DOT 1 (-8450 4900);
DOT 1 (-8450 4950);
DOT 1 (-8450 5000);
DOT 1 (-8450 5050);
DOT 1 (-8450 5100);
DOT 1 (-8450 5150);
DOT 1 (-7600 4800);
DOT 1 (-7600 4750);
DOT 1 (-7600 4850);
DOT 1 (-7600 4950);
DOT 1 (-7600 4900);
DOT 1 (-7600 5000);
DOT 1 (-7600 5050);
DOT 1 (-7600 5100);
DOT 1 (-7600 5150);
DOT 1 (-8450 3800);
DOT 1 (-8450 3850);
DOT 1 (-8450 3950);
DOT 1 (-8450 4050);
DOT 1 (-8450 4100);
DOT 1 (-8450 4200);
DOT 1 (-8450 4150);
DOT 1 (-7600 3800);
DOT 1 (-7600 3850);
DOT 1 (-7600 3900);
DOT 1 (-7600 3950);
DOT 1 (-7600 4000);
DOT 1 (-7600 4050);
DOT 1 (-7600 4100);
DOT 1 (-7600 4150);
DOT 1 (-7600 4200);
DOT 1 (-8450 3900);
DOT 1 (-8450 4000);
DOT 1 (-7600 5750);
DOT 1 (-7600 5950);
DOT 1 (-6000 5725);
DOT 1 (-6000 5775);
DOT 1 (-6000 5825);
DOT 1 (-6000 5875);
DOT 1 (-6000 5975);
DOT 1 (-6000 5925);
DOT 1 (-6000 6025);
DOT 1 (-6000 6075);
DOT 1 (-6000 6125);
DOT 1 (-5150 5725);
DOT 1 (-5150 5775);
DOT 1 (-5150 5825);
DOT 1 (-5150 5875);
DOT 1 (-5150 5975);
DOT 1 (-5150 5925);
DOT 1 (-5150 6025);
DOT 1 (-5150 6075);
DOT 1 (-5150 6125);
DOT 1 (-5150 4225);
DOT 1 (-6000 4225);
DOT 1 (-6000 4175);
DOT 1 (-5150 4175);
DOT 1 (-5150 4075);
DOT 1 (-5150 4125);
DOT 1 (-5150 4025);
DOT 1 (-5150 3975);
DOT 1 (-5150 3925);
DOT 1 (-5150 3825);
DOT 1 (-5150 3875);
DOT 1 (-6000 4125);
DOT 1 (-6000 4075);
DOT 1 (-6000 4025);
DOT 1 (-6000 3975);
DOT 1 (-6000 3925);
DOT 1 (-6000 3875);
DOT 1 (-6000 3825);
DOT 1 (-6000 4775);
DOT 1 (-6000 4825);
DOT 1 (-6000 4875);
DOT 1 (-6000 4925);
DOT 1 (-6000 4975);
DOT 1 (-6000 5025);
DOT 1 (-6000 5075);
DOT 1 (-5150 4775);
DOT 1 (-5150 4875);
DOT 1 (-5150 4925);
DOT 1 (-5150 4975);
DOT 1 (-5150 5075);
DOT 1 (-5150 5025);
DOT 1 (-6000 5125);
DOT 1 (-6000 5175);
DOT 1 (-5150 5175);
DOT 1 (-5150 5125);
DOT 1 (-5150 4825);
FORCENOTE
TP FAB3-DVT ADD COUPON SYMBOLS 20161118
(-3250 1900) 0;
DISPLAY LEFT (-3250 1900);
DISPLAY 1.021277 (-3250 1900);
PAINT RED (-3250 1900);
QUIT
